TITLE: Bill of Materials
DATE: 08/15/2023
DESIGN: t6g
TEMPLATE: c:\cadence\spb_17.2\share\cdssetup\template.bom
CALLOUT: 

S.No.,PART_NUMBER,DESCRIPTION,MATERIAL,Qty,Ref Des,QPN,LIFECYCLE,STANDARD,ROOM
0,AJ033040001,IC CTRL(68P)CYUSB3304-68LTXI(QFN),IC,1,U6001,?,?,?,USB3_HUB1_CYP
1,AJ051610U03,IC(354P)PT5161LRS(FC-CSP),IC,8,"U6010,U6011,U6012,U6013,U6014,U6015,U6016,U6017",?,Comp-Approve,End of Design,?
2,AJ094000T08,IC(484P)LCMXO3LF-9400C-5BG484C(CABGA),IC,1,U18,?,?,?,?
3,AKE30Z00613,IC(8P) EEPROM M24128-BWMN6TP(SO8),IC,2,"U1,U64",?,?,?,?
4,AKE30Z00613,IC(8P) EEPROM M24128-BWMN6TP(SO8),IC,1,U6003,?,?,?,USB3_HUB1_CYP
5,AKE33Z00600,IC EEPROM(8P)M24M02-DRMN6TP(SO),IC,8,"U11,U12,U15,U16,U17,U19,U20,U21",?,?,?,?
6,AL000125003,IC OTHER(24P)DS125BR111RTWR(WQFN),IC,1,U6000,?,?,?,PCIE REDRIVER BOM2
7,AL000128K00,IC OTHER(16P)ADC128D818CIMTX/NOPB(TSSOP),IC,2,"U51,U269",?,?,?,ADC_TI_BOM1
8,AL000211007,IC OTHER(12P) TUSB211IRWBR(QFN),EMPTY,1,U5201,?,?,?,USB2 BOM2
9,AL000251002,IC(24P)9FGL0251DKILFT(VFQFPN),IC,1,U247,?,?,?,?
10,AL000304005,IC(12P)PI4ULS3V304AZMAEX(UQFN),IC,1,U54,?,?,?,?
11,AL000304K01,IC OTHER(8P) PI6CV304LE(TSSOP),IC,1,U90,?,?,?,?
12,AL000331011,IC OTHER(5P) AP331AWG-7 (SOT25),EMPTY,1,U8006,?,?,?,HSC BOM2
13,AL000331011,IC OTHER(5P) AP331AWG-7 (SOT25),IC,2,"U8008,U8010",?,?,?,?
14,AL000451003,IC OTHER(32P) 9ZXL0451EKILFT(VFQFPN),IC,2,"U10,U314",?,?,?,?
15,AL000698000,IC OTHER(4P) NCP698SQ15T1G(SC82-AB),EMPTY,1,U167,?,Comp-Approve,End of Design,?
16,AL000852001,IC CTRL(28P) GL852G-OHY60(QFN),IC,1,U268,?,?,?,USB2 BOM1
17,AL001G66000,IC(5P) 74LVC1G66GV(SOT753),IC,2,"U320,U321",?,?,?,?
18,AL002G07003,IC OTHER(6P)74LVC2G07DW-7(SOT-363),IC,8,"U8,U58,U59,U134,U211,U255,U257,U308",?,?,?,?
19,AL002G07003,IC OTHER(6P)74LVC2G07DW-7(SOT-363),EMPTY,1,U8004,?,?,?,?
20,AL002G07006,IC(6P) SN74LVC2G07DCKR(SC70-6),IC,3,"U29,U40,U259",?,Comp-Approve,End of Design,?
21,AL003112004,IC(9P)IML3112-Y2B000NCG8(DFN),EMPTY,1,U213,?,?,?,?
22,AL003126K08,IC OTHER(14P) 74CBTLV3126PW(TSSOP),IC,4,"U7,U67,U222,U223",?,?,?,?
23,AL003284002,IC (37P)NCP3284AMNTXG(PQFN),IC,1,PU9,?,?,?,?
24,AL004307000,IC OTHER(8P) LTC4307CMS8#TRPBF(MSOP),IC,4,"U175,U192,U194,U200",?,?,?,?
25,AL004307000,IC OTHER(8P) LTC4307CMS8#TRPBF(MSOP),EMPTY,1,U176,?,?,?,?
26,AL005016007,IC (10P) MP5016GQH-L-Z(QFN),IC,2,"PU205,PU207",?,?,?,NIC_P3V3_BOM2
27,AL005016007,IC (10P) MP5016GQH-L-Z(QFN),IC,1,PU293,?,?,?,E1S_P3V3_BOM2
28,AL005991A00,IC(32P)MP5991GLU-Z(LGA),IC,4,"PU287,PU288,PU296,PU297",?,?,?,HSC BOM1
29,AL006700001,IC OTHER(6P)LT6700CS6-1#TRPBF(TSOT-23),EMPTY,1,U142,?,?,?,HSC BOM2
30,AL006700001,IC OTHER(6P)LT6700CS6-1#TRPBF(TSOT-23),EMPTY,1,U206,?,?,?,?
31,AL0075BD000,IC OTHER (8P) LM75BD(SO8),IC,4,"U270,U271,U272,U273",?,?,?,?
32,AL007718001,IC OTHER(8P) NCT7718W(MSOP),IC,1,U143,?,?,?,HSC BOM2
33,AL008042000,IC OTHER(64P) TUSB8042AIRGCR(VQFN),IC,1,U6002,?,?,?,USB3_HUB2
34,AL008626000,IC CTRL(14P)MPQ8626GD-Z(QFN),IC,2,"PU6000,PU6001",?,?,?,?
35,AL008633005,IC CTRL(21P) MPQ8633BGLE-C838-Z(QFN),IC,4,"PU3,PU57,PU6500,PU6501",?,?,?,?
36,AL008633007,IC CTRL(21P)MPQ8633AGLE-C807-Z(QFN),IC,2,"PU55,U326",?,?,?,?
37,AL009306K04,IC OTHER(8P)PCA9306DP1(TSSOP),IC,1,U98,?,?,?,?
38,AL009539K07,IC OTHER(24P)PCA9539RPW(TSSOP),IC,1,U181,?,?,?,?
39,AL009548K02,IC OTHER(24P) TCA9548APWR(TSSOP),IC,4,"U22,U36,U39,U6020",?,?,?,?
40,AL009617K02,IC OTHER(8P) PCA9617ADP(TSSOP),IC,6,"U2,U27,U96,U235,U236,U279",?,?,?,?
41,AL009617K02,IC OTHER(8P) PCA9617ADP(TSSOP),EMPTY,1,U5,?,?,?,?
42,AL009818001,IC OTHER(3P)RT9818C-44GV(SOT23-3),IC,1,U100,?,?,?,?
43,AL011617W00,IC CTRL(16P)MAX11617EEE+T QSOP,EMPTY,2,"U50,U193",?,?,?,ADC_MAM_BOM2
44,AL012902001,IC OTHER(30P)PI3EQX12902AZLEX(TQFN),IC,1,U237,?,?,?,PCIE REDRIVER BOM1
45,AL015080B00,IC OTHER(28P)MAX15090BEWI+T(WLP),IC,2,"PU200,PU202",?,?,?,NIC_P3V3_BOM1
46,AL015080B00,IC OTHER(28P)MAX15090BEWI+T(WLP),IC,2,"PU201,PU203",?,?,?,NIC_P12V_MAM_TIC_BOM1
47,AL015080B00,IC OTHER(28P)MAX15090BEWI+T(WLP),IC,1,PU294,?,?,?,E1S_P12V_MAM_TIC_BOM1
48,AL015080B00,IC OTHER(28P)MAX15090BEWI+T(WLP),IC,1,PU295,?,?,?,E1S_P3V3_BOM1
49,AL015080B00,IC OTHER(28P)MAX15090BEWI+T(WLP),IC,1,PU300,?,?,?,SCM_P12V_MAM_BOM1
50,AL028022003,IC(16P)ISL28022FRZ-T(QFN),IC,9,"U52,U55,U56,U263,U264,U265,U266,U276,U6005",?,?,?,?
51,AL02T245000,IC OTHER (10P) SN74AVC2T245RSWR(UQFN),IC,3,"U146,U147,U152",?,Comp-Approve,End of Design,?
52,AL031312000,IC(22P)RS31312R(QFN),IC,2,"PU204,PU206",?,?,?,NIC_P12V_MPS_MAM_BOM2
53,AL031312000,IC(22P)RS31312R(QFN),IC,1,PU292,?,?,?,E1S_P12V_MPS_MAM_BOM2
54,AL031312000,IC(22P)RS31312R(QFN),IC,1,PU299,?,?,?,SCM_P12V_MPS_BOM2
55,AL04T774K00,IC OTHER(16P) SN74AVC4T774PWR(TSSOP),IC,6,"U53,U116,U148,U149,U150,U151",?,?,?,?
56,AL069260000,IC CTRL(40P)ISL69260IRAZ-T(QFN),IC,2,"PU6502,PU6510",?,?,?,?
57,AL071715001,IC(5P)TPS71715DCKR(SC70),EMPTY,1,U9,?,?,?,?
58,AL080929000,IC OTHER(3P) APX809-29SAG-7(SOT23),IC,3,"U6006,U8001,U8002",?,?,?,?
59,AL080929000,IC OTHER(3P) APX809-29SAG-7(SOT23),IC,1,U8003,?,?,?,E1S_P3V3_BOM2
60,AL099390004,IC CTRL(41P) ISL99390FRZ-TR5935(QFN),IC,46,"PU2,PU4,PU5,PU6,PU10,PU11,PU13,PU14,PU15,PU16,PU17,PU18,PU19,PU20,PU22,PU23,PU24,PU26,PU27,PU28,PU29,PU30,PU31,PU32,PU33,PU35,PU36,PU37,PU38,PU39,PU40,PU43,PU44,PU45,PU46,PU47,PU48,PU49,PU50,PU51,PU52,PU53,PU6503,PU6504,PU6511,PU6512",?,?,?,?
61,AL1G0007001,IC OTHER(5P) 74LVC1G07GV(SOT753),IC,4,"U104,U157,U218,U219",?,?,?,?
62,AL1G0007024,IC(5P) SN74LVC1G07DCKR(SOP),IC,10,"U3,U28,U30,U33,U34,U82,U86,U92,U101,U124",?,?,?,?
63,AL1G0007024,IC(5P) SN74LVC1G07DCKR(SOP),EMPTY,1,U99,?,?,?,?
64,AL1G0008020,IC OTHER(5P) 74LVC1G08W5-7(SOT25),IC,7,"U23,U31,U35,U278,U9001,U9050,U9051",?,?,?,?
65,AL1G0017K01,IC OTHER(5P) 74LVC1G17GW(TSSOP),IC,3,"U44,U75,U207",?,?,?,?
66,AL1G0126009,IC OTHER(5P) 74LVC1G126SE-7 (SOT353),IC,8,"U66,U204,U217,U224,U225,U239,U286,U8082",?,?,?,?
67,AL2G0017005,IC(6P) 74LVC2G17GW (SC-88),IC,6,"U195,U196,U252,U253,U256,U316",?,?,?,?
68,AL2G0066C00,IC OTHER(8P) SN74AUC2G66DCTR (SSOP),IC,4,"U13,U14,U153,U154",?,?,?,?
69,AL3CSW12000,IC(10P)PI3CSW12ZUAEX(UQFN),IC,14,"U4,U6,U41,U42,U43,U45,U46,U47,U48,U49,U105,U106,U107,U108",?,?,?,?
70,AL404025013,IC OTHER(3P)LM4040AIM3X-2.5/NOPB(SOT23),EMPTY,1,U8005,?,?,?,HSC BOM2
71,AL404025013,IC OTHER(3P)LM4040AIM3X-2.5/NOPB(SOT23),IC,2,"U8007,U8009",?,?,?,?
72,ALLV4052K19,IC OTHERS(16P)74LV4052PW(TSSOP),IC,2,"U160,U212",?,?,?,?
73,ALLVC1G1000,IC OTHER(6P)SN74LVC1G11DCKR(SC70),IC,1,U38,?,Comp-Approve,End of Design,?
74,ALSB3157000,IC(6P) NC7SB3157P6X(SC70-6),EMPTY,4,"U243,U244,U245,U246",?,Comp-Approve,End of Design,?
75,ALSB3157000,IC OTHER(6P)NC7SB3157P6X(SC70-6),IC,1,U8000,?,Comp-Approve,End of Design,?
76,ALVC1G32007,IC(5P)74LVC1G32GW (SC70-5),IC,3,"U37,U248,U9002",?,?,?,?
77,ALVC2G08K01,IC OTHER(8P) 74LVC2G08DP(TSSOP),EMPTY,3,"U240,U241,U242",?,?,?,?
78,AR0F0TP4023,PROG IC(45P)MP5990GMA-1111-Z(F9C2)(LGA),IC,1,PU289,?,?,?,HSC BOM1
79,ARF0TGP4002,PROG IC(49P)RAA229620GNP#HA0(QFN) (checksum:C6AD1D27/9A3E4D0C),IC,4,"PU12,PU25,PU34,PU42",?,?,?,?
80,ARF0TGP4003,PROG IC(41P)RAA229621GNP#HA0(QFN) (checksum:B68CAFAB),IC,2,"PU21,PU54",?,?,?,?
81,BA039040020,"TRANS SMD METR3904-G(40V,200MA,0.225W)",IC,1,Q6001,?,?,?,HSC BOM2
82,BAM01380023,"TRANS MOS NX138BK(60V,265MA,310MW)",IC,4,"Q12,Q29,Q30,Q61",?,?,?,?
83,BAM01380032,"TRANS MOSFET BSS138DW-7-F(50V,200MA)",IC,3,"Q18,Q19,Q27",?,?,?,?
84,BAM138K0000,"TRANS MOS BSS138K(50V,0.22A,0.35W)",IC,9,"PQ14,PQ15,PQ16,PQ17,Q62,Q63,Q64,U24,U32",?,Comp-Approve,End of Design,?
85,BAM138K0000,"TRANS MOS BSS138K(50V,0.22A,0.35W)",EMPTY,1,U325,?,Comp-Approve,End of Design,?
86,BAM138K0003,"TRANS MOSFET PJT138K(50V,0.36A,0.236W)",IC,50,"Q1,Q3,Q37,Q50,Q67,Q69,Q70,Q71,Q72,Q74,Q75,Q78,Q79,Q80,Q81,Q83,Q84,Q85,Q86,Q87,Q95,Q96,Q101,Q102,Q103,Q104,Q106,Q107,Q108,Q128,Q129,Q130,Q131,Q132,Q133,Q134,Q135,Q136,Q137,Q144,Q145,Q146,Q148,Q6000,Q8000,Q8001,Q9000,Q9001,Q9002,Q9003",?,?,?,?
87,BAM138K0003,"TRANS MOSFET PJT138K(50V,0.36A,0.236W)",IC,2,"Q118,Q123",?,?,?,NIC_P12V_MAM_TIC_BOM1
88,BAM138K0003,"TRANS MOSFET PJT138K(50V,0.36A,0.236W)",IC,2,"Q119,Q124",?,?,?,NIC_P3V3_BOM1
89,BAM138K0003,"TRANS MOSFET PJT138K(50V,0.36A,0.236W)",IC,1,Q125,?,?,?,SCM_P12V_MAM_BOM1
90,BAM138K0003,"TRANS MOSFET PJT138K(50V,0.36A,0.236W)",IC,1,Q126,?,?,?,E1S_P3V3_BOM1
91,BAM138K0003,"TRANS MOSFET PJT138K(50V,0.36A,0.236W)",IC,1,Q127,?,?,?,E1S_P12V_MAM_TIC_BOM1
92,BAM20350002,"TRANS MOS DMP2035U-7(-20V,-4.9A,0.81W)",EMPTY,2,"Q7000,Q7002",?,?,?,?
93,BAM34150008,"TRANS MOS PJA3415AE(-20V,-4.3A,1.25W)",IC,4,"PQ10,PQ11,PQ12,PQ13",?,?,?,?
94,BAM70020002,"TR MOSFET 2N7002K(60V,300MA,0.35W)SOT-23",IC,6,"Q39,Q54,U158,U190,U290,U324",?,?,?,?
95,BAM70020002,"TR MOSFET 2N7002K(60V,300MA,0.35W)SOT-23",EMPTY,1,U6004,?,?,?,HSC BOM2
96,BAM70020047,"TRANS MOS 2N7002KDW(60V115MA,0.2W)SOT363",IC,5,"Q2,Q4,Q8,Q11,Q28",?,?,?,?
97,BAMNR580000,"TRANS MOS PSMNR58-30YLH(30V,380A,333W)",IC,7,"PPQ1,PPQ2,PPQ5,PPQ6,PPQ7,PPQ8,PPQ9",?,?,?,HSC BOM2
98,BAMNR580000,"TRANS MOS PSMNR58-30YLH(30V,380A,333W)",IC,2,"Q56,Q57",?,?,?,?
99,BAMNR580000,"TRANS MOS PSMNR58-30YLH(30V,380A,333W)",EMPTY,2,"Q7001,Q7003",?,?,?,?
100,BC000340Z30,"DIODE SMD B340A-13-F(40V,3A)SCHOTTKY",IC,7,"PD102,PD103,PD108,PD109,PD112,PD113,PD116",?,?,?,?
101,BC000530Z41,"DIODE SMD B0530WS-7-F(30V,0.5A)SOD-323",EMPTY,4,"D8003,D8004,D8005,D8006",?,Comp-Approve,End of Design,?
102,BC015P3SZ00,"DIODE SMD SS15P3S-M3/86A(30V,15A)",IC,1,PD111,?,?,?,HSC BOM1
103,BC015P3SZ00,"DIODE SMD SS15P3S-M3/86A(30V,15A)",IC,1,PD17,?,?,?,HSC BOM2
104,BC0BAT54Z53,DIODE BAT54-7-F(30V.200MA SCHOTTKY),IC,1,D1,?,?,?,?
105,BC0MDJ14000,"DIODE SMD 5.0SMDJ14A(14V,216A,5000W)",IC,2,"PD13,PD15",?,?,?,?
106,BCBAT54CZ13,"DIODE SMD BAT54CW(30V,0.2A,SOT323)",IC,1,U166,?,?,?,?
107,BCBAT54CZ13,"DIODE SMD BAT54CW(30V,0.2A,SOT323)",EMPTY,2,"U57,U60",?,?,?,?
108,BCSMF14AZ01,"DIODE SMF14A(14V,8.6A)SOD-123FL",IC,4,"PD101,PD107,PD114,PD115",?,?,?,?
109,BEBL0172Z00,LED SMD(2P) BLUE(LTST-C281TBKT-5A),IC,26,"D5,D9,D46,D49,D73,D74,D75,D76,D77,D78,D79,D80,D81,D82,D83,D84,D85,D88,D91,D93,D96,D98,D99,D6000,D8000,D8001",?,?,?,?
110,BEYL0159Z00,LED SMD(2P)YELLOW(LTST-C190KSKT-P),IC,4,"D6,D7,D8,D8002",?,?,?,?
111,BF650000032,"OSC SMD 50MHZ(25PPM,15PF,3.3V)FK5000023",OSC,1,OSC1,?,?,?,?
112,BG6120000B0,"XTAL 12MHZ(+-20PPM,10PF)8Z12000006",MISC,1,Y8004,?,?,?,USB2 BOM1
113,BG624000101,"XTAL SMD 24MHZ(+-30PPM,18PF)7M24020002",MISC,1,Y6000,?,?,?,USB3_HUB2
114,BG6250000L4,"XTAL SMD 25MHZ(+-10PPM,8PF)E3SB25E000004",MISC,1,Y8003,?,?,?,?
115,BG626000049,"XTAL 26MHZ(10PPM,11PF)8Z26000054",MISC,1,Y9,?,?,?,USB3_HUB1_CYP
116,BG632768012,"CRYSTAL SMD 32.768KHZ(+-20PPM,12.5PF)",IC,1,Y3,?,Comp-Approve,End of Design,?
117,BG632768012,"CRYSTAL SMD 32.768KHZ(+-20PPM,12.5PF)",EMPTY,1,Y5,?,Comp-Approve,End of Design,?
118,BG648000076,"XTAL SMD 48MHZ(10PPM, 12PF)FL4800106",MISC,2,"Y2,Y4",?,?,?,?
119,CC71003MZ30,"CAP OSCON SMD 100U 16V(20%,5*5.8)NPN",OSCON,4,"PC473,PC6561,PC6619,PC6810",?,?,?,?
120,CC72201MZ28,"CAP OSCON SMD 220U 6.3V(20%,5*5.8)NPN",ALUM,1,PC1845,?,?,?,?
121,CC72703MD38,"CAPOSCON DIP 270U16V(20%,ESR10,6.3*8)NPN",OSCON,13,"PC3,PC101,PC104,PC164,PC220,PC272,PC273,PC336,PC491,PC492,PC522,PC566,PC596",?,?,?,?
122,CC72703MZ11,"CAP OSCON SMD 270U 16V(20%,6.3*7.7)NPN",OSCON,5,"PC390,PC393,PC454,PC6800,PC6801",?,?,?,?
123,CC7390JMZ13,"CAP OSCON SMD 390U 2.5V(20%,5*5.8)NPN",ALUM,22,"PC89,PC115,PC228,PC229,PC230,PC530,PC531,PC532,PC801,PC803,PC6513,PC6532,PC6571,PC6572,PC6573,PC6574,PC6629,PC6630,PC6631,PC6632,PC6804,PC6805",?,?,?,?
124,CC75601MD16,"CAP OSCON DIP 560U 6.3V(+-20%,6.3*8)NPN",OSCON,2,"PC1866,PC1867",?,?,?,?
125,CH-106T0B00,"CAP CHIP 1P 50V(+-0.05P,COG,0402)",COG,9,"C6093,C6096,C6099,C6102,C6106,C6109,C6112,C6115,C6119",?,?,?,USB3_HUB2
126,CH-10KMEE00,"CAP CHIP 1U 4V(+-20%,X6S,0201)",X6S,136,"C123,C125,C126,C135,C138,C185,C186,C187,C188,C190,C201,C202,C203,C204,C222,C243,C257,C265,C280,C285,C289,C293,C294,C301,C306,C307,C314,C315,C326,C330,C337,C342,C346,C353,C374,C375,C376,C382,C384,C386,C387,C389,C390,C391,C394,C407,C415,C418,C422,C423,C425,C440,C441,C442,C448,C452,C453,C454,C455,C456,C459,C460,C470,C485,C488,C491,C492,C497,C512,C513,C514,C521,C525,C526,C528,C529,C539,C542,C545,C555,C562,C570,C573,C577,C581,C597,C598,C599,C607,C609,C613,C618,C620,C621,C622,C624,C643,C647,C653,C654,C655,C660,C673,C676,C677,C779,C781,C783,C786,C787,C788,C792,C793,C797,C975,C978,C979,C980,C983,C998,C999,C1000,C1006,C1013,C1015,C1016,C1017,C1018,C1019,C1020,C1024,C1027,C1031,C1039,C1046,C1050",?,Comp-Approve,End of Design,?
127,CH-276B0B00,"CAP CHIP 2.7P 50V(+-0.1P,NPO,0402)",NPO,2,"C236,C237",?,?,?,?
128,CH-3916TB01,"CAP CHIP 3.9P 50V(+-0.1P,NPO,0402)",NPO,2,"C213,C214",?,?,?,?
129,CH-4716TB06,CAP CHIP 4.7P 50V(+-0.1P.NPO.0402),NPO,2,"C71,C94",?,?,?,?
130,CH-8216TB09,CAP CHIP 8.2P 50V (+-0.1P NP0 0402),NP0,2,"C215,C216",?,?,?,?
131,CH01006JB08,"CAP CHIP 10P 50V(+-5%,C0G,0402)",EMPTY,12,"C295,C296,C297,C298,C299,C302,C303,C304,C305,C308,C309,C310",?,?,?,?
132,CH0106F0B00,CHIP0402,NPO,3,"C238,C239,PC569",?,?,?,?
133,CH01206JB05,CAP CHIP 12P 50V(+-5%.C0G.0402),C0G,1,C91,?,?,?,USB3_HUB1_CYP
134,CH01506JB06,CAP CHIP 15P 50V(+-5% C0G 0402),C0G,2,"C2029,C2030",?,?,?,USB2 BOM1
135,CH01506JB06,CAP CHIP 15P 50V(+-5% C0G 0402),C0G,1,C93,?,?,?,USB3_HUB1_CYP
136,CH02706JB06,CAP CHIP 27P 50V(+-5% NPO 0402),NPO,2,"C6090,C6091",?,?,?,USB3_HUB2
137,CH03306JB04,CHIP0402,NPO,3,"C1510,C1511,C1512",?,?,?,?
138,CH03906JB06,CAP CHIP 39P 50V(+-5%.NPO.0402),NPO,2,"PC2157,PC2168",?,?,?,NIC_P3V3_BOM2
139,CH03906JB06,CAP CHIP 39P 50V(+-5%.NPO.0402),NPO,1,PC2197,?,?,?,E1S_P3V3_BOM2
140,CH04706JB01,CHIP0402,NPO,1,PC1877,?,?,?,?
141,CH11006JB00,"CAP CHIP 100P 50V(+-5%,NPO,0402)",NPO,2,"C1209,PC132",?,?,?,?
142,CH11006JB00,"CAP CHIP 100P 50V(+-5%,NPO,0402)",NPO,1,PC2167,?,?,?,NIC_P12V_MPS_MAM_BOM2
143,CH11006JB18,CAP CHIP 100P 50V(+-5%.X7R.0402),EMPTY,16,"C35,C59,C1078,C1079,C1080,C1081,C1082,C1083,C1084,C1085,C1344,C2042,C2043,C2044,C2045,C2176",?,Comp-Approve,End of Design,ADC_MAM_BOM2
144,CH11006JB18,CAP CHIP 100P 50V(+-5%.X7R.0402),X7R,2,"PC1322,PC2162",?,Comp-Approve,End of Design,NIC_P3V3_BOM2
145,CH11006JB18,CAP CHIP 100P 50V(+-5%.X7R.0402),X7R,1,PC2203,?,Comp-Approve,End of Design,E1S_P3V3_BOM2
146,CH11506JB08,CHIP0402,NPO,2,"PC6515,PC6534",?,?,?,?
147,CH12206JB00,CAP CHIP 220P 50V(+-5%.COG.0402),C0G,4,"C62,C63,C363,C364",?,?,?,?
148,CH12206KB14,"CAP CHIP 220P 50V(+-10%,X7R,0402)",X7R,1,PC2182,?,?,?,HSC BOM1
149,CH12206KB14,"CAP CHIP 220P 50V(+-10%,X7R,0402)",EMPTY,3,"PC2183,PC2224,PC2225",?,?,?,HSC BOM1
150,CH12206KB14,"CAP CHIP 220P 50V(+-10%,X7R,0402)",X7R,2,"PC64,PC259",?,?,?,?
151,CH122KM8801,"CAP CHIP 220U 4V(20%,7343,SPCAP)MAT",SPCAP,20,"PC97,PC98,PC100,PC102,PC103,PC105,PC106,PC108,PC275,PC276,PC277,PC279,PC387,PC388,PC389,PC391,PC494,PC495,PC496,PC498",?,?,?,?
152,CH1336K1B02,"CAP CHIP 330P 50V(+-10%,X7R,0402)",X7R,2,"PC852,PC6019",?,?,?,?
153,CH14706KB18,CHIP0402,X7R,1,C6028,?,?,?,USB3_HUB1_CYP
154,CH14706KB18,CHIP0402,X7R,12,"PC77,PC78,PC198,PC250,PC253,PC367,PC368,PC469,PC472,PC523,PC643,PC6607",?,?,?,?
155,CH1566K1B09,"CAP CHIP 560P 50V(+-10%,X7R,0402)",EMPTY,46,"PC141,PC149,PC154,PC157,PC158,PC159,PC163,PC166,PC168,PC169,PC170,PC173,PC174,PC175,PC176,PC177,PC178,PC179,PC180,PC181,PC182,PC184,PC185,PC187,PC188,PC189,PC190,PC191,PC192,PC195,PC201,PC202,PC205,PC206,PC207,PC208,PC255,PC315,PC316,PC317,PC318,PC321,PC6564,PC6585,PC6622,PC6641",?,?,?,?
156,CH1566K1B09,"CAP CHIP 560P 50V(+-10%,X7R,0402)",X7R,1,PC2340,?,?,?,SCM_P12V_MPS_BOM2
157,CH1566K1B09,"CAP CHIP 560P 50V(+-10%,X7R,0402)",X7R,1,PC2341,?,?,?,E1S_P12V_MPS_MAM_BOM2
158,CH21006JB10,"CAP CHIP 1000P 50V(+-5%,X7R,0402)",EMPTY,17,"C101,C107,C196,C248,C465,C467,C5015,C8000,C8070,C8072,C8246,C8360,C8362,C8641,C9000,C9001,C9002",?,?,?,?
159,CH21006JB10,"CAP CHIP 1000P 50V(+-5%,X7R,0402)",X7R,33,"C109,C197,C242,C249,C461,C468,C642,C5000,C5001,C5002,C5003,C5004,C5005,C5006,C5009,C5010,C5011,C5012,C5013,C5014,C5016,C5017,C5018,C5019,C5020,C5022,C5023,C5024,C6758,C8066,C8069,C8356,C8359",?,?,?,?
160,CH21006K917,"CAP CHIP 1000P 50V(+-10%,X7R,0603)",X7R,1,C1786,?,Comp-Approve,End of Design,HSC BOM2
161,CH21006KB16,"CAP CHIP 1N 50V(+-10%,X7R,0402)EP",EMPTY,1,PC1751,?,?,?,HSC BOM2
162,CH21006KB16,"CAP CHIP 1N 50V(+-10%,X7R,0402)EP",EMPTY,4,"PC2347,PC2348,PC2349,PC2350",?,?,?,HSC BOM1
163,CH2336K1B12,CHIP0402,X7R,18,"PC68,PC71,PC194,PC244,PC245,PC358,PC361,PC384,PC463,PC464,PC639,PC6016,PC6540,PC6555_1,PC6578_2,PC6600,PC6613_1,PC6634_2",?,?,?,?
164,CH23906KB14,"CAP CHIP 3900P 50V(+-10%,X7R,0402)",X7R,2,"PC2150,PC4056",?,?,?,NIC_P12V_MAM_TIC_BOM1
165,CH23906KB14,"CAP CHIP 3900P 50V(+-10%,X7R,0402)",X7R,1,PC2215,?,?,?,E1S_P12V_MAM_TIC_BOM1
166,CH23906KB14,"CAP CHIP 3900P 50V(+-10%,X7R,0402)",X7R,1,PC2237,?,?,?,SCM_P12V_MAM_BOM1
167,CH2686K1B01,"CAP CHIP 6800P 50V(+-10%,X7R,0402)",X7R,2,"PC2089,PC2151",?,?,?,NIC_P3V3_BOM1
168,CH2686K1B01,"CAP CHIP 6800P 50V(+-10%,X7R,0402)",X7R,1,PC2216,?,?,?,E1S_P3V3_BOM1
169,CH30106KB19,"CAP CHIP 0.001U 50V(10%,X7R,0402)",EMPTY,12,"C207,C208,C209,C210,C211,C212,C230,C231,C232,C233,C234,C235",?,Comp-Release Qty,End of Design,?
170,CH30106KB19,"CAP CHIP 0.001U 50V(10%,X7R,0402)",X7R,4,"C85,C87,C604,C605",?,Comp-Release Qty,End of Design,?
171,CH30106KB19,"CAP CHIP 0.001U 50V(10%,X7R,0402)",X7R,10,"C6054,C6056,C6058,C6060,C6062,C6067,C6069,C6071,C6073,C6075",?,Comp-Release Qty,End of Design,USB3_HUB1_CYP
172,CH30106KB19,"CAP CHIP 0.001U 50V(10%,X7R,0402)",X7R,1,PC2192,?,Comp-Release Qty,End of Design,HSC BOM1
173,CH31006KB18,"CAP CHIP 0.01U 50V(+-10%,X7R,0402)",EMPTY,3,"C22,C86,C1520",?,?,?,?
174,CH31006KB18,"CAP CHIP 0.01U 50V(+-10%,X7R,0402)",EMPTY,2,"C40,PC2088",?,?,?,NIC_P12V_MAM_TIC_BOM1
175,CH31006KB18,"CAP CHIP 0.01U 50V(+-10%,X7R,0402)",X7R,1,C551,?,?,?,?
176,CH31006KB18,"CAP CHIP 0.01U 50V(+-10%,X7R,0402)",X7R,20,"C6033,C6035,C6037,C6039,C6040,C6045,C6049,C6051,C6053,C6055,C6057,C6059,C6061,C6063,C6068,C6070,C6072,C6074,C6076,C6080",?,?,?,USB3_HUB1_CYP
177,CH31006KB18,"CAP CHIP 0.01U 50V(+-10%,X7R,0402)",X7R,9,"C6094,C6097,C6100,C6103,C6107,C6110,C6113,C6116,C6120",?,?,?,USB3_HUB2
178,CH31006KB18,"CAP CHIP 0.01U 50V(+-10%,X7R,0402)",EMPTY,2,"PC2144,PC2149",?,?,?,NIC_P3V3_BOM1
179,CH31006KB18,"CAP CHIP 0.01U 50V(+-10%,X7R,0402)",X7R,2,"PC2189,PC2190",?,?,?,HSC BOM1
180,CH31006KB18,"CAP CHIP 0.01U 50V(+-10%,X7R,0402)",EMPTY,1,PC2213,?,?,?,E1S_P3V3_BOM1
181,CH31006KB18,"CAP CHIP 0.01U 50V(+-10%,X7R,0402)",EMPTY,1,PC2214,?,?,?,E1S_P12V_MAM_TIC_BOM1
182,CH31006KB18,"CAP CHIP 0.01U 50V(+-10%,X7R,0402)",EMPTY,1,PC2236,?,?,?,SCM_P12V_MAM_BOM1
183,CH3104K1B11,"CAP CHIP 0.01U 25V(+-10%,X7R,0402)MUR",EMPTY,2,"PC6005,PC6006",?,?,?,?
184,CH3224K1B01,"CAP CHIP 0.022U 25V(+-10%,X7R,0402)",X7R,2,"PC153,PC258",?,?,?,?
185,CH3334K1B00,"CAP CHIP 33NF 25V(+-10%,X7R,0402)",EMPTY,1,PC1750,?,?,?,HSC BOM2
186,CH3474K1B04,CAP CHIP 0.047U 25V(+-10% X7R 0402),X7R,2,"PC2155,PC2166",?,?,?,NIC_P12V_MPS_MAM_BOM2
187,CH3474K1B04,CAP CHIP 0.047U 25V(+-10% X7R 0402),X7R,1,PC2193,?,?,?,HSC BOM1
188,CH3474K1B04,CAP CHIP 0.047U 25V(+-10% X7R 0402),X7R,1,PC2232,?,?,?,SCM_P12V_MPS_BOM2
189,CH3474K1B04,CAP CHIP 0.047U 25V(+-10% X7R 0402),X7R,1,PC2281,?,?,?,E1S_P12V_MPS_MAM_BOM2
190,CH3683K1B09,"CAP CHIP 0.068UF 16V(+-10%,X7R 0402)",X7R,2,"PC1321,PC2161",?,?,?,NIC_P3V3_BOM2
191,CH3683K1B09,"CAP CHIP 0.068UF 16V(+-10%,X7R 0402)",X7R,5,"PC2184,PC2185,PC2191,PC2226,PC2227",?,?,?,HSC BOM1
192,CH3683K1B09,"CAP CHIP 0.068UF 16V(+-10%,X7R 0402)",X7R,1,PC2201,?,?,?,E1S_P3V3_BOM2
193,CH4102K6E00,"CAP CHIP 0.1U 10V(+-10%,X7S,0201)",X7S,186,"C129,C130,C131,C133,C134,C137,C139,C141,C184,C189,C191,C192,C198,C205,C206,C217,C228,C253,C260,C264,C266,C281,C282,C283,C287,C288,C290,C291,C292,C300,C311,C312,C313,C316,C319,C322,C334,C340,C341,C344,C349,C350,C365,C377,C378,C379,C380,C381,C383,C385,C388,C392,C393,C395,C396,C397,C400,C403,C411,C421,C426,C427,C428,C430,C443,C444,C445,C446,C447,C449,C450,C451,C457,C458,C462,C463,C464,C473,C477,C481,C493,C495,C496,C498,C500,C515,C516,C517,C519,C520,C522,C523,C524,C538,C540,C541,C543,C544,C558,C566,C576,C578,C580,C582,C583,C585,C600,C601,C602,C603,C606,C608,C610,C614,C615,C616,C617,C619,C623,C627,C631,C635,C650,C657,C658,C659,C662,C664,C774,C775,C776,C777,C778,C780,C782,C784,C785,C789,C790,C791,C794,C800,C804,C968,C972,C982,C984,C985,C987,C989,C1001,C1002,C1003,C1004,C1005,C1007,C1008,C1009,C1010,C1011,C1012,C1014,C1021,C1035,C1043,C1047,C1048,C1051,C1052,C1053,C1055,C1057,C1066,C1067,C1068,C1069,C1070,C1071,C1072,C1073,C7500,C7501,C7502,C7503,C7504,C7510",?,Comp-Approve,End of Design,?
194,CH4103K1B08,"CAP CHIP 0.1U 16V(10%,X7R,0402)",X7R,44,"C20,C194,C352,C355,C356,C357,C358,C359,C360,C361,C362,C1126,C1127,C1128,C1129,C1131,C1132,C1133,C1134,C1171,C1172,C1173,C1174,C1175,C1176,C1503,C1504,C1505,C1506,C1507,C1508,C1509,C1513,C1514,C1515,C1516,C1517,C1518,C1519,C1521,C1522,C1523,C1554,C1563",?,?,?,?
195,CH4103K1B08,"CAP CHIP 0.1U 16V(10%,X7R,0402)",X7R,1,C1787,?,?,?,HSC BOM2
196,CH4104K1B00,"CAP CHIP 0.1U 25V(+-10%,X7R,0402)",X7R,395,"C1,C2,C3,C4,C5,C7,C8,C10,C11,C12,C13,C14,C15,C16,C17,C18,C19,C21,C23,C25,C26,C27,C30,C31,C32,C36,C38,C42,C43,C58,C68,C69,C70,C72,C73,C75,C78,C79,C80,C81,C84,C88,C90,C92,C95,C96,C97,C98,C99,C100,C104,C106,C108,C112,C116,C120,C124,C128,C132,C136,C140,C144,C148,C152,C156,C160,C164,C168,C172,C176,C180,C218,C219,C223,C224,C226,C347,C508,C552,C553,C592,C593,C611,C612,C629,C639,C640,C641,C693,C1058,C1059,C1060,C1061,C1062,C1063,C1064,C1065,C1074,C1075,C1096,C1097,C1102,C1103,C1104,C1105,C1106,C1107,C1108,C1109,C1110,C1111,C1112,C1235,C1236,C1237,C1238,C1239,C1240,C1274,C1275,C1278,C1279,C1282,C1283,C1305,C1323,C1336,C1337,C1338,C1339,C1347,C1352,C1354,C1592,C1663,C1707,C1708,C1713,C1751,C1754,C1756,C1757,C1766,C1769,C1770,C1772,C1773,C1774,C1775,C1796,C1797,C1802,C1803,C1804,C1809,C1810,C1821,C1822,C1823,C1824,C1825,C1826,C1827,C1831,C1832,C1833,C1834,C1835,C1836,C1837,C1838,C1839,C1840,C1841,C1859,C1860,C1861,C1862,C1873,C1874,C1875,C1876,C1877,C1878,C1879,C1880,C1881,C1882,C1886,C1889,C1923,C1924,C1925,C1957,C1958,C1963,C1973,C1974,C1975,C1976,C1977,C1978,C1979,C1988,C1997,C1998,C2010,C2012,C2013,C2014,C2015,C2017,C2018,C2019,C2020,C2021,C2022,C2024,C2027,C2056,C2067,C2069,C2071,C2257,C2329,C2334,C2339,C2344,C6000,C6086,C6087,C6500,C8005,C8006,C8007,C8008,C8009,C9005,C9007,C9008,C9050,C9051,PC4,PC5,PC6,PC7,PC8,PC9,PC10,PC11,PC12,PC13,PC14,PC15,PC21,PC29,PC62,PC67,PC74,PC83_2,PC84_1,PC85,PC85_1,PC86_2,PC93,PC95,PC96,PC99,PC107,PC111_6,PC113,PC113_4,PC114_3,PC114_6,PC115_4,PC116_3,PC124_6,PC127,PC127_6,PC128,PC132_5,PC134_5,PC136,PC136_6,PC141_6,PC145_7,PC146_8,PC148,PC148_1,PC149_2,PC150_6,PC153_6,PC175_9,PC176_10,PC177_3,PC178_4,PC193,PC201_1,PC202_2,PC207_1,PC208_2,PC215,PC222,PC243,PC254_1,PC255_2,PC260_1,PC261_2,PC278,PC284_3,PC285_4,PC290_3,PC293_4,PC306_5,PC309_5,PC317_7,PC318_8,PC325_1,PC326_2,PC338,PC345_9,PC348_3,PC357,PC364,PC373_2,PC374_1,PC375,PC375_1,PC376_2,PC392,PC403_4,PC404_3,PC405_4,PC408_3,PC422_5,PC425_5,PC435_7,PC436_8,PC438,PC438_1,PC439_2,PC462,PC473_1,PC474_2,PC479,PC479_1,PC482_2,PC497,PC503_1,PC504_2,PC509_1,PC510_2,PC511,PC544_3,PC545_4,PC551_4,PC552_3,PC566_5,PC570_5,PC577,PC577_7,PC578_8,PC583,PC583_1,PC586_2,PC599,PC605_9,PC609_3,PC620_9,PC621_10,PC622_3,PC623_4,PC638,PC819,PC1852,PC1853,PC1869,PC2091,PC2092,PC2137,PC2152,PC2217,PC2218,PC2238,PC6002,PC6003,PC6004,PC6007,PC6514,PC6518,PC6533,PC6537,PC6562,PC6602,PC6620",?,?,?,?
197,CH4104K1B00,"CAP CHIP 0.1U 25V(+-10%,X7R,0402)",EMPTY,23,"C6,C64,C65,C66,C67,C74,C105,C345,C348,C674,C675,C1561,C6085,C6757,C8001,C8002,C8003,C8004,C8011,C8013,PC514,PC1870,PC6601",?,?,?,?
198,CH4104K1B00,"CAP CHIP 0.1U 25V(+-10%,X7R,0402)",X7R,20,"C33,C37,C1086,C1087,C1088,C1089,C1090,C1091,C1092,C1093,C1094,C1095,C2046,C2047,C2048,C2049,C2050,C2051,C2052,C2194",?,?,?,ADC_TI_BOM1
199,CH4104K1B00,"CAP CHIP 0.1U 25V(+-10%,X7R,0402)",X7R,8,"C1863,C1864,C1865,C1866,C1868,C1869,C1870,C1871",?,?,?,PCIE REDRIVER BOM1
200,CH4104K1B00,"CAP CHIP 0.1U 25V(+-10%,X7R,0402)",X7R,5,"C2032,C2033,C2034,C2039,C2040",?,?,?,USB2 BOM1
201,CH4104K1B00,"CAP CHIP 0.1U 25V(+-10%,X7R,0402)",X7R,4,"C6003,C6004,C6023,C6024",?,?,?,USB3_HUB1
202,CH4104K1B00,"CAP CHIP 0.1U 25V(+-10%,X7R,0402)",X7R,6,"C6005,C6006,C6007,C6008,C6011,C6012",?,?,?,PCIE REDRIVER BOM2
203,CH4104K1B00,"CAP CHIP 0.1U 25V(+-10%,X7R,0402)",X7R,15,"C6013,C6014,C6017,C6018,C6025,C6026,C6095,C6098,C6101,C6104,C6108,C6111,C6114,C6117,C6121",?,?,?,USB3_HUB2
204,CH4104K1B00,"CAP CHIP 0.1U 25V(+-10%,X7R,0402)",X7R,13,"C6032,C6034,C6036,C6038,C6041,C6044,C6048,C6050,C6052,C6064,C6077,C6081,C6083",?,?,?,USB3_HUB1_CYP
205,CH4104K1B00,"CAP CHIP 0.1U 25V(+-10%,X7R,0402)",EMPTY,1,C6084,?,?,?,HSC BOM2
206,CH4104K1B00,"CAP CHIP 0.1U 25V(+-10%,X7R,0402)",X7R,1,C8010,?,?,?,E1S_P3V3_BOM2
207,CH4104K1B00,"CAP CHIP 0.1U 25V(+-10%,X7R,0402)",X7R,1,PC1789,?,?,?,HSC BOM2
208,CH4104K1B00,"CAP CHIP 0.1U 25V(+-10%,X7R,0402)",X7R,2,"PC2160,PC2174",?,?,?,NIC_P12V_MPS_MAM_BOM2
209,CH4104K1B00,"CAP CHIP 0.1U 25V(+-10%,X7R,0402)",X7R,1,PC2206,?,?,?,E1S_P12V_MPS_MAM_BOM2
210,CH4104K1B00,"CAP CHIP 0.1U 25V(+-10%,X7R,0402)",X7R,1,PC2241,?,?,?,SCM_P12V_MPS_BOM2
211,CH4104KEB00,"CAP CHIP 0.1U 25V(+-10%,X6S,0402)",EMPTY,3,"C5232,C5234,C5236",?,Comp-Approve,End of Design,USB2 BOM2
212,CH4104KEB00,"CAP CHIP 0.1U 25V(+-10%,X6S,0402)",X6S,6,"PC1648,PC1649,PC6000,PC6001,PC6500,PC6519",?,Comp-Approve,End of Design,?
213,CH4106K1B01,"CAP CHIP 100NF 50V(+-10%,X7R,0402)",X7R,29,"C61,C193,C1042,C1227,C1332,C2179,C6122,C8019,C8022,PC451,PC524,PC6020,PC6021,PC6022,PC6023,PC6543,PC6553_1,PC6563,PC6565,PC6576,PC6584,PC6603,PC6611_1,PC6621,PC6623,PC6640,PC6646,PC6806,PC6807",?,?,?,?
214,CH4106K1B01,"CAP CHIP 100NF 50V(+-10%,X7R,0402)",EMPTY,3,"C8014,C8015,C8016",?,?,?,HSC BOM2
215,CH4106K1B01,"CAP CHIP 100NF 50V(+-10%,X7R,0402)",EMPTY,4,"C8017,C8018,C8020,C8021",?,?,?,?
216,CH4106K1B01,"CAP CHIP 100NF 50V(+-10%,X7R,0402)",X7R,1,PC2156,?,?,?,NIC_P12V_MPS_MAM_BOM2
217,CH4106K1B01,"CAP CHIP 100NF 50V(+-10%,X7R,0402)",X7R,1,PC2202,?,?,?,E1S_P12V_MPS_MAM_BOM2
218,CH4106K1B01,"CAP CHIP 100NF 50V(+-10%,X7R,0402)",X7R,1,PC2235,?,?,?,SCM_P12V_MPS_BOM2
219,CH4221MEE01,"CAP CHIP 0.22UF 6.3V(20%,X6S,0201)_DIFF BUS",X6S,598,"C41,C44,C46,C47,C48,C49,C50,C51,C52,C53,C54,C55,C56,C678,C679,C680,C681,C682,C683,C684,C685,C686,C687,C688,C689,C690,C691,C692,C694,C695,C696,C697,C698,C699,C700,C701,C702,C703,C704,C705,C706,C707,C708,C709,C710,C711,C712,C713,C714,C715,C716,C717,C718,C719,C720,C721,C722,C723,C724,C725,C726,C727,C728,C729,C730,C731,C732,C733,C734,C735,C736,C737,C738,C739,C740,C741,C742,C743,C744,C745,C746,C747,C748,C749,C750,C751,C752,C753,C754,C755,C756,C757,C758,C759,C760,C761,C762,C763,C764,C765,C766,C767,C768,C769,C770,C771,C772,C773,C806,C807,C808,C809,C810,C811,C812,C813,C814,C815,C816,C817,C818,C819,C820,C821,C822,C823,C824,C825,C826,C827,C828,C829,C830,C831,C832,C833,C834,C835,C836,C837,C838,C839,C840,C841,C842,C843,C844,C845,C846,C847,C848,C849,C850,C851,C852,C853,C854,C855,C856,C857,C858,C859,C860,C861,C862,C863,C864,C865,C866,C867,C868,C869,C870,C871,C872,C873,C874,C875,C876,C877,C878,C879,C880,C881,C882,C883,C884,C885,C886,C887,C888,C889,C890,C891,C892,C893,C894,C895,C896,C897,C898,C899,C900,C901,C902,C903,C904,C905,C906,C907,C908,C909,C910,C911,C912,C913,C914,C915,C916,C917,C918,C919,C920,C921,C922,C923,C924,C925,C926,C927,C928,C929,C930,C931,C932,C933,C934,C935,C936,C937,C938,C939,C940,C941,C942,C943,C944,C945,C946,C947,C948,C949,C950,C951,C952,C953,C954,C955,C956,C957,C958,C959,C960,C961,C962,C963,C964,C965,C1098,C1099,C1100,C1101,C1524,C1525,C1526,C1527,C1528,C1529,C1530,C1531,C1532,C1533,C1534,C1535,C1536,C1537,C1538,C1539,C1540,C1541,C1542,C1543,C1544,C1545,C1546,C1547,C1548,C1549,C1550,C1552,C1553,C1555,C1556,C1557,C1558,C1559,C1560,C1565,C1566,C1568,C1569,C1570,C1571,C1572,C1573,C1574,C1575,C1576,C1577,C1578,C1579,C1792,C1793,C1794,C1989,C1990,C1991,C1992,C1993,C1994,C1995,C1996,C2073,C2074,C2075,C2076,C2077,C2078,C6501,C6502,C6503,C6504,C6505,C6506,C6507,C6508,C6509,C6510,C6511,C6512,C6513,C6514,C6515,C6516,C6517,C6518,C6519,C6520,C6521,C6522,C6523,C6524,C6525,C6526,C6527,C6528,C6529,C6530,C6531,C6532,C6533,C6534,C6535,C6536,C6537,C6538,C6539,C6540,C6541,C6542,C6543,C6544,C6545,C6546,C6547,C6548,C6549,C6550,C6551,C6552,C6553,C6554,C6555,C6556,C6557,C6558,C6559,C6560,C6561,C6562,C6563,C6564,C6565,C6566,C6567,C6568,C6569,C6570,C6571,C6572,C6573,C6574,C6575,C6576,C6577,C6578,C6579,C6580,C6581,C6582,C6583,C6584,C6585,C6586,C6587,C6588,C6589,C6590,C6591,C6592,C6593,C6594,C6595,C6596,C6597,C6598,C6599,C6600,C6601,C6602,C6603,C6604,C6605,C6606,C6607,C6608,C6609,C6610,C6611,C6612,C6613,C6614,C6615,C6616,C6617,C6618,C6619,C6620,C6621,C6622,C6623,C6624,C6625,C6626,C6627,C6628,C6629,C6630,C6631,C6632,C6633,C6634,C6635,C6636,C6637,C6638,C6639,C6640,C6641,C6642,C6643,C6644,C6645,C6646,C6647,C6648,C6649,C6650,C6651,C6652,C6653,C6654,C6655,C6656,C6657,C6658,C6659,C6660,C6661,C6662,C6663,C6664,C6665,C6666,C6667,C6668,C6669,C6670,C6671,C6672,C6673,C6674,C6675,C6676,C6677,C6678,C6679,C6680,C6681,C6682,C6683,C6684,C6685,C6686,C6687,C6688,C6689,C6690,C6691,C6692,C6693,C6694,C6695,C6696,C6697,C6698,C6699,C6700,C6701,C6702,C6703,C6704,C6705,C6706,C6707,C6708,C6709,C6710,C6711,C6712,C6713,C6714,C6715,C6716,C6717,C6718,C6719,C6720,C6721,C6722,C6723,C6724,C6725,C6726,C6727,C6728,C6729,C6730,C6731,C6732,C6733,C6734,C6735,C6736,C6737,C6738,C6739,C6740,C6741,C6742,C6743,C6744,C6745,C6746,C6747,C6748,C6749,C6750,C6751,C6752,C6753,C6754,C6755,C6756,C9102,C9103,C9104,C9105",?,?,?,?
220,CH4223K1B00,"CAP CHIP 0.22U 16V(10%,X7R,0402)",X7R,46,"PC19,PC92,PC94,PC117,PC121,PC122,PC133,PC137,PC146,PC155,PC156,PC161,PC183,PC186,PC209,PC217,PC218,PC270,PC271,PC300,PC301,PC314,PC333,PC334,PC353,PC383,PC386,PC413,PC414,PC428,PC445,PC447,PC489,PC490,PC519,PC520,PC560,PC561,PC574,PC593,PC594,PC612,PC630,PC631,PC6507,PC6526",?,Comp-Approve,End of Design,?
221,CH4223K1B00,"CAP CHIP 0.22U 16V(10%,X7R,0402)",X7R,2,"PC2153,PC2164",?,Comp-Approve,End of Design,NIC_P12V_MPS_MAM_BOM2
222,CH4223K1B00,"CAP CHIP 0.22U 16V(10%,X7R,0402)",X7R,1,PC2196,?,Comp-Approve,End of Design,E1S_P12V_MPS_MAM_BOM2
223,CH4223K1B00,"CAP CHIP 0.22U 16V(10%,X7R,0402)",X7R,1,PC2229,?,Comp-Approve,End of Design,SCM_P12V_MPS_BOM2
224,CH4224K1B01,"CAP CHIP 0.22U 25V(10%,X7R,0402)",X7R,6,"C29,C9226,PC568,PC641,PC1847,PC6017",?,Comp-Release Qty,End of Design,?
225,CH4331KEB01,"CAP CHIP 0.33UF 6.3V(10%,X6S,0402)_FOR DIFF BUS",X6S,4,"C6015,C6016,C6019,C6020",?,Comp-Approve,End of Design,USB3_HUB1
226,CH4331KEB01,"CAP CHIP 0.33UF 6.3V(10%,X6S,0402)_FOR DIFF BUS",X6S,2,"C6021,C6022",?,Comp-Approve,End of Design,USB3_HUB2
227,CH5101K1B01,"CAP CHIP 1U,6.3V(+-10%,X7R,0402)",X7R,4,"PC73,PC247,PC363,PC466",?,?,?,?
228,CH5103K1900,CHIP0603,X7R,1,PC8008,?,Comp-Approve,End of Design,?
229,CH5103KEB01,"CAP CHIP 1UF 16V(10%,X6S,0402)",X6S,11,"PC75,PC200,PC252,PC365,PC471,PC645,PC1846,PC6544,PC6545,PC6604,PC6605",?,?,?,?
230,CH5104KEB02,"CAP CHIP 1UF 25V(+-10%,X6S,0402)",X6S,74,"C45,C1564,C1567,C1884,C2007,C2041,PC20,PC22,PC87_1,PC88_2,PC115_6,PC117_4,PC118,PC118_3,PC126,PC128_6,PC135_5,PC140_6,PC150_1,PC151_2,PC154_6,PC179_3,PC180_4,PC209_1,PC210_2,PC212,PC237,PC262_1,PC263_2,PC291_4,PC292_3,PC310_5,PC323_1,PC324_2,PC349_3,PC377_1,PC378_2,PC406_3,PC407_4,PC424_5,PC440_1,PC441_2,PC480_2,PC481_1,PC511_1,PC512_2,PC550_3,PC553_4,PC569_5,PC584_2,PC585_1,PC608_3,PC624_3,PC625_4,PC1848,PC2079,PC2139,PC2140,PC2207,PC2208,PC2230,PC5328,PC6008,PC6009,PC6010,PC6011,PC6505,PC6506,PC6524,PC6525,PC6554_1,PC6577_2,PC6612_1,PC6633_2",?,?,?,?
231,CH5104KEB02,"CAP CHIP 1UF 25V(+-10%,X6S,0402)",X6S,2,"C2031,C2035",?,?,?,USB2 BOM1
232,CH5104KEB02,"CAP CHIP 1UF 25V(+-10%,X6S,0402)",X6S,7,"C2317,C6031,C6043,C6047,C6065,C6078,C6082",?,?,?,USB3_HUB1_CYP
233,CH5104KEB02,"CAP CHIP 1UF 25V(+-10%,X6S,0402)",X6S,4,"C39,PC2086,PC2093,PC2147",?,?,?,NIC_P3V3_BOM1
234,CH5104KEB02,"CAP CHIP 1UF 25V(+-10%,X6S,0402)",EMPTY,1,C5229,?,?,?,USB2 BOM2
235,CH5104KEB02,"CAP CHIP 1UF 25V(+-10%,X6S,0402)",X6S,1,C6009,?,?,?,PCIE REDRIVER BOM2
236,CH5104KEB02,"CAP CHIP 1UF 25V(+-10%,X6S,0402)",X6S,1,C6089,?,?,?,USB3_HUB2_TI
237,CH5104KEB02,"CAP CHIP 1UF 25V(+-10%,X6S,0402)",X6S,1,C6092,?,?,?,USB3_HUB2
238,CH5104KEB02,"CAP CHIP 1UF 25V(+-10%,X6S,0402)",EMPTY,3,"C9,C8012,C9004",?,?,?,?
239,CH5104KEB02,"CAP CHIP 1UF 25V(+-10%,X6S,0402)",EMPTY,1,C9003,?,?,?,HSC BOM2
240,CH5104KEB02,"CAP CHIP 1UF 25V(+-10%,X6S,0402)",X6S,8,"PC1525,PC2103,PC2181,PC2186,PC2187,PC2188,PC2223,PC3272",?,?,?,HSC BOM1
241,CH5104KEB02,"CAP CHIP 1UF 25V(+-10%,X6S,0402)",X6S,4,"PC2085,PC2087,PC2098,PC2146",?,?,?,NIC_P12V_MAM_TIC_BOM1
242,CH5104KEB02,"CAP CHIP 1UF 25V(+-10%,X6S,0402)",X6S,2,"PC2154,PC2165",?,?,?,NIC_P12V_MPS_MAM_BOM2
243,CH5104KEB02,"CAP CHIP 1UF 25V(+-10%,X6S,0402)",X6S,2,"PC2159,PC2169",?,?,?,NIC_P3V3_BOM2
244,CH5104KEB02,"CAP CHIP 1UF 25V(+-10%,X6S,0402)",X6S,1,PC2198,?,?,?,E1S_P12V_MPS_MAM_BOM2
245,CH5104KEB02,"CAP CHIP 1UF 25V(+-10%,X6S,0402)",X6S,1,PC2200,?,?,?,E1S_P3V3_BOM2
246,CH5104KEB02,"CAP CHIP 1UF 25V(+-10%,X6S,0402)",X6S,2,"PC2209,PC2211",?,?,?,E1S_P12V_MAM_TIC_BOM1
247,CH5104KEB02,"CAP CHIP 1UF 25V(+-10%,X6S,0402)",X6S,2,"PC2210,PC2212",?,?,?,E1S_P3V3_BOM1
248,CH5104KEB02,"CAP CHIP 1UF 25V(+-10%,X6S,0402)",X6S,1,PC2231,?,?,?,SCM_P12V_MPS_BOM2
249,CH5104KEB02,"CAP CHIP 1UF 25V(+-10%,X6S,0402)",X6S,2,"PC2233,PC2234",?,?,?,SCM_P12V_MAM_BOM1
250,CH5222KEB01,"CAP CHIP 2.2UF 10V(+-10%,X6S,0402)",X6S,92,"PC79,PC80,PC81_C1P0_1,PC82_C1P0_2,PC109,PC110,PC111_C1P0_4,PC112,PC112_C1P0_3,PC113_C1P0_6,PC125,PC126_C0P1_6,PC131,PC133_C1P0_5,PC138,PC139_C1P1_6,PC142,PC143,PC144_IOP0_2,PC147_IOP0_1,PC151,PC152_C0P0_6,PC171,PC172,PC173_IOP0_4,PC174_IOP0_3,PC203,PC204,PC205_11P0_1,PC206_11P0_2,PC256,PC257,PC258_C0P1_1,PC259_C0P1_2,PC286,PC287,PC288_C0P1_3,PC289_C0P1_4,PC307,PC308_C0P1_5,PC319,PC320,PC321_SOP1_1,PC322_SOP1_2,PC346,PC347_SOP1_3,PC369,PC370,PC371_C1P1_1,PC372_C1P1_2,PC399,PC400,PC401_C1P1_4,PC402_C1P1_3,PC421,PC423_C1P1_5,PC432,PC433,PC434_IOP1_2,PC437_IOP1_1,PC475,PC476,PC477_C0P0_1,PC478_C0P0_2,PC505,PC506,PC507_11P1_1,PC508_11P1_2,PC546,PC547,PC548_C0P0_3,PC549_C0P0_4,PC567,PC568_C0P0_5,PC579,PC580,PC581_SOP0_1,PC582_SOP0_2,PC606,PC607_SOP0_3,PC616,PC617,PC618_IOP1_4,PC619_IOP1_3,PC6550_09P0_1,PC6551_09P0_2,PC6552,PC6575,PC6609_09P1_1,PC6610,PC6644_09P1_2,PC6645",?,?,?,?
251,CH5223KE901,"CAP CHIP 2.2U 16V(+-10%,X6S,0603)",X6S,1,PC591,?,?,?,?
252,CH5223M1900,"CAP CHIP 2.2UF 16V(20%,X7R,0603)",X7R,2,"PC1320,PC2158",?,?,?,NIC_P12V_MPS_MAM_BOM2
253,CH5223M1900,"CAP CHIP 2.2UF 16V(20%,X7R,0603)",X7R,1,PC2205,?,?,?,E1S_P12V_MPS_MAM_BOM2
254,CH5223M1900,"CAP CHIP 2.2UF 16V(20%,X7R,0603)",X7R,1,PC2239,?,?,?,SCM_P12V_MPS_BOM2
255,CH5471MEB01,"CAP CHIP 4.7UF 6.3V(+-20%,X6S,0402)",X6S,56,"C121,C122,C195,C200,C221,C227,C241,C256,C258,C325,C331,C336,C338,C343,C371,C373,C406,C412,C413,C416,C419,C438,C439,C469,C472,C483,C484,C494,C510,C511,C554,C557,C569,C571,C572,C594,C596,C638,C644,C649,C651,C652,C670,C672,C967,C970,C976,C977,C981,C996,C997,C1034,C1038,C1045,C1054,C1056",?,?,?,?
256,CH5473KE902,"CAP CHIP 4.7UF 16V(+-10%,X6S,0603)",X6S,1,PC581,?,?,?,?
257,CH6101MEB01,"CAP CHIP 10UF 6.3V(+-20%,X6S,0402)",X6S,66,"C28,C76,C77,C82,C83,C118,C119,C127,C199,C250,C254,C261,C269,C286,C321,C332,C333,C339,C354,C370,C372,C410,C414,C420,C429,C431,C436,C437,C480,C482,C489,C490,C499,C506,C507,C561,C567,C574,C579,C584,C591,C595,C626,C645,C646,C648,C661,C669,C671,C796,C803,C971,C973,C986,C994,C995,C1023,C1036,C1037,C1044,C1049,C2328,C2512,C2515,C2659,C2662",?,?,?,?
258,CH6101MEB01,"CAP CHIP 10UF 6.3V(+-20%,X6S,0402)",X6S,1,C2038,?,?,?,USB2 BOM1
259,CH6101MEB01,"CAP CHIP 10UF 6.3V(+-20%,X6S,0402)",EMPTY,1,C24,?,?,?,?
260,CH6101MEB03,"CAP CHIP 10UF 6.3V(+-20%,X6S,0402)MUR",X6S,8,"PC76,PC199,PC251,PC366,PC470,PC644,PC6546,PC6606",?,?,?,?
261,CH6103KEA00,"CAP CHIP 10UF 16V(+-10%,X6S,0805)",X6S,8,"C1076,C1077,C1170,C1331,C1333,C1340,C1767,C1768",?,?,?,?
262,CH6103KEA00,"CAP CHIP 10UF 16V(+-10%,X6S,0805)",EMPTY,2,"C57,C60",?,?,?,?
263,CH6103KEA00,"CAP CHIP 10UF 16V(+-10%,X6S,0805)",X6S,1,C6010,?,?,?,PCIE REDRIVER BOM2
264,CH6103KEA00,"CAP CHIP 10UF 16V(+-10%,X6S,0805)",X6S,1,C6088,?,?,?,USB3_HUB2_MRP
265,CH6103KEA01,"CAP CHIP 10UF 16V(+-10%,X6S,0805)MUR",X6S,8,"PC2081,PC2082,PC2142,PC2143,PC2219,PC2220,PC2240,PC2280",?,?,?,?
266,CH6103KEA01,"CAP CHIP 10UF 16V(+-10%,X6S,0805)MUR",X6S,2,"PC2163,PC2173",?,?,?,NIC_P3V3_BOM2
267,CH6103KEA01,"CAP CHIP 10UF 16V(+-10%,X6S,0805)MUR",X6S,1,PC2204,?,?,?,E1S_P3V3_BOM2
268,CH6104KEA00,"CAP CHIP 10U 25V(+-10%,X6S,0805,H1.25)",X6S,50,"C89,C142,C143,C145,C146,C147,C149,C150,C151,C153,C154,C155,C157,C158,C159,C161,C162,C163,C165,C166,C167,C169,C170,C171,C173,C174,C175,C177,C178,C179,C181,C182,C183,C509,C518,C527,C530,C531,C532,C533,C534,C535,C536,C537,C546,C547,C548,C549,C1883,C5032",?,?,?,?
269,CH6104KEA00,"CAP CHIP 10U 25V(+-10%,X6S,0805,H1.25)",X6S,1,C1867,?,?,?,PCIE REDRIVER BOM1
270,CH6104KEA00,"CAP CHIP 10U 25V(+-10%,X6S,0805,H1.25)",X6S,2,"C6105,C6118",?,?,?,USB3_HUB2
271,CH6221ME900,"CAP CHIP 22U 6.3V(+-20%,X6S,0603)",X6S,3,"C1920,C1921,C9922",?,?,?,?
272,CH6221ME900,"CAP CHIP 22U 6.3V(+-20%,X6S,0603)",X6S,5,"C6030,C6042,C6046,C6066,C6079",?,?,?,USB3_HUB1_CYP
273,CH6222MEA01,"CAP CHIP 22U 10V(+-20%,X6S,0805)MUR",X6S,5,"PC1599,PC1600,PC1855,PC1856,PC1868",?,?,?,?
274,CH6223MEA00,"CAP CHIP 22U 16V(+-20%,X6S,0805)",EMPTY,3,"C1113,C1114,C1115",?,?,?,?
275,CH6223MEA00,"CAP CHIP 22U 16V(+-20%,X6S,0805)",X6S,4,"C34,C1213,C1829,C1830",?,?,?,?
276,CH6223MEA00,"CAP CHIP 22U 16V(+-20%,X6S,0805)",X6S,1,C6027,?,?,?,USB3_HUB1_CYP
277,CH6223MEA01,"CAP CHIP 22UF 16V(+-20%,X6S,0805)MUR",X6S,233,"C1276,C1277,PC27,PC60,PC61,PC81,PC89_1,PC90_2,PC91_1,PC93_2,PC95_1,PC96_2,PC111,PC116_6,PC118_6,PC119,PC119_4,PC119_6,PC120,PC120_3,PC123,PC123_4,PC124_3,PC125_4,PC126_3,PC129,PC129_6,PC130,PC130_6,PC132_6,PC134,PC135,PC136_5,PC138_5,PC139_5,PC144_6,PC145_6,PC147_6,PC150,PC152,PC152_1,PC153_2,PC154_1,PC157_2,PC157_6,PC158_1,PC158_6,PC159_2,PC159_6,PC181_3,PC182_4,PC184_3,PC185_4,PC187_3,PC188_4,PC211_1,PC212_2,PC213_1,PC214_2,PC215_1,PC216_2,PC218_2,PC219_1,PC227,PC254,PC264_1,PC265_2,PC266_1,PC267_2,PC268_1,PC269_2,PC294_3,PC295_4,PC296_3,PC297_4,PC298_3,PC299_4,PC311_5,PC312_5,PC313_5,PC327_1,PC328_2,PC329_1,PC330_2,PC331_1,PC332_2,PC334_1,PC335_2,PC350_3,PC351_3,PC352_3,PC353_3,PC379_1,PC380_2,PC381_1,PC382_2,PC384_1,PC385_2,PC409_4,PC410_3,PC411_4,PC412_3,PC415_4,PC416_3,PC426_5,PC427_5,PC429_5,PC442_1,PC443_2,PC444_1,PC446_2,PC448_1,PC449_2,PC483_1,PC484_2,PC485_1,PC486_2,PC487_1,PC488_2,PC513_1,PC514_2,PC515_1,PC516_2,PC517_1,PC518_2,PC521_1,PC554_3,PC555_4,PC556_3,PC557_4,PC558_3,PC559_4,PC570,PC571,PC571_5,PC572_5,PC573_5,PC576,PC587_1,PC588_2,PC589_1,PC590_2,PC591_1,PC592_2,PC593_1,PC595_2,PC610_3,PC611_3,PC612_3,PC613_3,PC626_3,PC627_4,PC628_3,PC629_4,PC632_3,PC633_4,PC1849,PC1850,PC1898,PC2080,PC2141,PC2242,PC2260,PC2261,PC2262,PC2263,PC2342,PC2343,PC2344,PC6012,PC6013,PC6014,PC6015,PC6501,PC6502,PC6503,PC6504,PC6520,PC6521,PC6522,PC6523,PC6556_1,PC6557_1,PC6558_1,PC6559_1,PC6560,PC6579_2,PC6580_2,PC6581_2,PC6582_2,PC6583,PC6614_1,PC6615_1,PC6616_1,PC6617_1,PC6618,PC6635_2,PC6636_2,PC6637_2,PC6638_2,PC6639,PC6802,PC6803,PC6816,PC6817,PC6818,PC6819,PC6900,PC6901,PC6902,PC6903,PC6904,PC6905,PC7000,PC7001,PC7002,PC7003,PC8000,PC8001,PC8002,PC8003,PC8004,PC8005,PC8006,PC8007,PC8009,PC8010,PC8011,PC8012,PC8013,PC8014,PC8071,PC8567",?,?,?,?
278,CH622KMEA03,"CAP CHIP 22U 4V(+-20%,X6S,0805)MUR",X6S,116,"PC65,PC83,PC84,PC102_1,PC105_1,PC106_2,PC108_2,PC114,PC120_6,PC123_6,PC127_4,PC128_4,PC129_3,PC130_3,PC134_6,PC135_6,PC140_5,PC141_5,PC148_6,PC149_6,PC163_6,PC166_1,PC166_6,PC168_2,PC169_1,PC170_2,PC189_4,PC190_3,PC191_4,PC192_3,PC221_2,PC224_1,PC225_2,PC227_1,PC280_2,PC281_1,PC282_2,PC283_1,PC285,PC288,PC302_3,PC303_4,PC304_3,PC305_4,PC315_5,PC316_5,PC339_2,PC341_1,PC342_2,PC344_1,PC354_3,PC355_3,PC394_2,PC395_1,PC397_2,PC398_1,PC417_3,PC418_4,PC419_3,PC420_4,PC430_5,PC431_5,PC456_1,PC458_2,PC459_1,PC460_2,PC499_2,PC500_1,PC501_2,PC502_1,PC523_2,PC526_1,PC527_2,PC529_1,PC562_3,PC563_4,PC564_3,PC565_4,PC575_5,PC576_5,PC600_2,PC602_1,PC603_2,PC604_1,PC614_3,PC615_3,PC634_4,PC635_3,PC636_4,PC637_3,PC850,PC865,PC866,PC867,PC6018,PC6024,PC6025,PC6026,PC6508,PC6509,PC6510,PC6511,PC6512,PC6527,PC6528,PC6529,PC6530,PC6531,PC6566_1,PC6567_1,PC6586_2,PC6587_2,PC6624_1,PC6625_1,PC6642_2,PC6643_2",?,?,?,?
279,CH622KMEA03,"CAP CHIP 22U 4V(+-20%,X6S,0805)MUR",EMPTY,4,"PC87,PC88,PC260,PC261",?,?,?,?
280,CH622KMEB02,"CAP CHIP 22UF 4V(+-20%,X6S,0402)",X6S,642,"C110,C111,C115,C117,C244,C245,C246,C251,C252,C255,C259,C262,C263,C267,C268,C270,C271,C272,C273,C274,C275,C276,C277,C278,C279,C284,C318,C327,C329,C335,C351,C368,C369,C399,C402,C408,C417,C424,C434,C435,C476,C478,C486,C487,C501,C504,C505,C563,C565,C568,C575,C586,C589,C590,C630,C634,C636,C656,C663,C667,C668,C799,C805,C969,C974,C988,C992,C993,C1026,C1030,C1032,C1040,C1041,C1922,C2102,C2103,C2104,C2105,C2106,C2107,C2108,C2109,C2110,C2111,C2112,C2113,C2114,C2115,C2116,C2117,C2118,C2119,C2120,C2121,C2122,C2123,C2124,C2125,C2126,C2127,C2128,C2129,C2130,C2131,C2132,C2133,C2134,C2135,C2136,C2137,C2138,C2139,C2140,C2141,C2142,C2143,C2144,C2145,C2146,C2147,C2148,C2149,C2150,C2151,C2152,C2153,C2154,C2155,C2156,C2157,C2158,C2159,C2160,C2161,C2162,C2163,C2164,C2165,C2166,C2167,C2169,C2170,C2171,C2173,C2174,C2175,C2177,C2178,C2181,C2182,C2183,C2185,C2186,C2189,C2190,C2192,C2193,C2195,C2196,C2198,C2199,C2201,C2202,C2203,C2204,C2205,C2207,C2208,C2209,C2210,C2211,C2213,C2214,C2215,C2216,C2217,C2219,C2220,C2221,C2222,C2223,C2225,C2226,C2227,C2228,C2229,C2231,C2232,C2233,C2234,C2237,C2238,C2239,C2240,C2243,C2244,C2245,C2246,C2248,C2249,C2250,C2251,C2253,C2254,C2255,C2256,C2258,C2259,C2260,C2261,C2262,C2263,C2264,C2265,C2266,C2267,C2268,C2269,C2270,C2271,C2272,C2273,C2274,C2275,C2276,C2277,C2278,C2279,C2280,C2281,C2282,C2283,C2284,C2285,C2286,C2287,C2288,C2289,C2290,C2291,C2292,C2293,C2294,C2295,C2296,C2297,C2298,C2300,C2301,C2302,C2303,C2304,C2306,C2307,C2308,C2309,C2310,C2312,C2313,C2314,C2315,C2316,C2318,C2319,C2320,C2321,C2322,C2324,C2325,C2326,C2327,C2330,C2331,C2332,C2333,C2335,C2336,C2337,C2338,C2340,C2341,C2342,C2343,C2345,C2346,C2347,C2348,C2350,C2351,C2352,C2353,C2354,C2356,C2357,C2358,C2359,C2360,C2362,C2363,C2364,C2365,C2366,C2368,C2369,C2370,C2371,C2372,C2374,C2375,C2376,C2377,C2378,C2380,C2381,C2382,C2383,C2386,C2387,C2388,C2389,C2392,C2393,C2394,C2395,C2397,C2398,C2399,C2400,C2402,C2403,C2404,C2405,C2407,C2408,C2409,C2410,C2411,C2412,C2413,C2414,C2415,C2416,C2417,C2418,C2419,C2420,C2421,C2422,C2423,C2424,C2425,C2426,C2427,C2428,C2429,C2430,C2431,C2432,C2433,C2434,C2435,C2436,C2437,C2438,C2439,C2440,C2441,C2442,C2443,C2444,C2445,C2446,C2447,C2448,C2449,C2450,C2451,C2452,C2453,C2454,C2455,C2456,C2457,C2458,C2459,C2460,C2461,C2462,C2463,C2464,C2465,C2466,C2467,C2468,C2469,C2470,C2471,C2472,C2473,C2474,C2475,C2476,C2477,C2478,C2479,C2480,C2481,C2482,C2483,C2484,C2485,C2486,C2487,C2488,C2489,C2490,C2491,C2492,C2493,C2494,C2495,C2496,C2497,C2498,C2499,C2500,C2501,C2502,C2503,C2504,C2505,C2506,C2507,C2508,C2509,C2510,C2511,C2513,C2514,C2516,C2517,C2518,C2520,C2521,C2522,C2523,C2524,C2525,C2526,C2527,C2528,C2529,C2530,C2531,C2532,C2533,C2534,C2535,C2536,C2537,C2538,C2539,C2540,C2541,C2542,C2543,C2544,C2545,C2546,C2547,C2548,C2549,C2550,C2551,C2552,C2553,C2554,C2555,C2556,C2557,C2558,C2559,C2560,C2561,C2562,C2563,C2564,C2565,C2566,C2567,C2568,C2569,C2570,C2571,C2572,C2573,C2574,C2575,C2576,C2577,C2578,C2579,C2580,C2581,C2582,C2583,C2584,C2585,C2586,C2587,C2588,C2589,C2590,C2591,C2592,C2593,C2594,C2595,C2596,C2597,C2598,C2599,C2600,C2601,C2602,C2603,C2604,C2605,C2606,C2607,C2608,C2609,C2610,C2611,C2612,C2613,C2614,C2615,C2616,C2617,C2618,C2619,C2620,C2621,C2622,C2623,C2624,C2625,C2626,C2627,C2628,C2629,C2630,C2631,C2632,C2633,C2634,C2635,C2636,C2637,C2638,C2639,C2640,C2641,C2642,C2643,C2644,C2645,C2646,C2647,C2648,C2649,C2650,C2651,C2652,C2653,C2654,C2655,C2656,C2657,C2658,C2660,C2661,C2663,C2664,C2665,C2667,C2668,C2669,C2670,C2671,C2672,C2673,C3888,C3889,C3890,C3891,C3892,C3893,C3894,C3895,C3896,C3897,C3898,C3899,C3900,C3901,C3902,C3903,C3904,C3905,C3906,C3907,C3908,C3909,C3910,C3911,C3912,C3913,C3914,C3915,C3916,C3917,C3918,C3919,C3920,C3921,C3922,C3925,C3926,C3927,C3928,C3929,C3930,C3931,C3932,C3933,C3934,C3935,C4178,C4179,C10179",?,Comp-Approve,End of Design,?
281,CH647KMEA04,"CAP CHIP 47U 4V(+-20%,X6S,0805)MUR",X6S,12,"C7002,C7003,C7006,C7007,C7033,C7034,C7035,C7036,C7038,C7039,C7040,C7041",?,?,?,?
282,CH710KMEA01,"CAP CHIP 100U 4V(+-20%,X6S,0805)MUR",X6S,64,"C102,C103,C113,C114,C220,C225,C229,C240,C247,C317,C320,C323,C324,C328,C366,C367,C398,C401,C404,C405,C409,C432,C433,C466,C471,C474,C475,C479,C502,C503,C550,C556,C559,C560,C564,C587,C588,C625,C628,C632,C633,C637,C665,C666,C795,C798,C801,C802,C966,C990,C991,C1022,C1025,C1028,C1029,C1033,C7010,C7013,C7016,C7019,C7022,C7025,C7028,C7031",?,?,?,?
283,CH747LM8818,"CAP CHIP 470U 2.5V(+-20%,7343,SPCAP)MAT",SPCAP,34,"C7000,C7001,C7004,C7005,C7008,C7009,C7011,C7012,C7014,C7015,C7017,C7018,C7020,C7021,C7023,C7024,C7026,C7027,C7029,C7030,C7032,C7037,PC534,PC6568,PC6569,PC6570,PC6626,PC6627,PC6628,PC6811,PC6812,PC6813,PC6814,PC6815",?,?,?,?
284,CH747LM8825,"CAPCHIP 470U 2.5V(20%,SP,ESR4.5,7343)MAT",EMPTY,4,"PC160,PC340,PC455,PC597",?,?,?,?
285,CH747LM8825,"CAPCHIP 470U 2.5V(20%,SP,ESR4.5,7343)MAT",SPCAP,14,"PC162,PC165,PC223,PC226,PC337,PC343,PC450,PC452,PC525,PC528,PC598,PC601,PC800,PC802",?,?,?,?
286,CS+001DFR10,RES CHIP 0.001 3W +-1%(2512)RLC_4P,CHIP,2,"R1837,R1838",?,?,?,?
287,CS+002AFR06,RES CHIP 0.002 2W +-1%(2512)EF,CHIP,8,"R1323,R1324,R1325,R3633,R3634,R3635,R3645,R3767",?,Comp-Approve,End of Design,?
288,CS+003AFR00,RES CHIP 0.003 2W +-1%(2512),CHIP,1,PR6002,?,?,?,HSC BOM2
289,CS-1002FB04,RES CHIP 1 1/16W +-1%(0402)EF,CHIP,10,"PR76,PR130,PR183,PR253,PR316,PR393,PR6538,PR6608,PR8389,R4077",?,Comp-Approve,End of Design,?
290,CS-1002FB04,RES CHIP 1 1/16W +-1%(0402)EF,CHIP,8,"PR2510,PR2511,PR2512,PR2513,PR2520,PR2521,PR2522,PR2523",?,Comp-Approve,End of Design,HSC BOM2
291,CS-1003F900,RES CHIP 1 1/10W +-1%(0603)EF,CHIP,4,"R555,R586,R4475,R4493",?,Comp-Approve,End of Design,?
292,CS-1504FB00,RES CHIP 1.5 1/8W +-1%(0402),EMPTY,46,"PR46,PR155,PR158,PR221,PR223,PR291,PR379,PR389,PR482,PR485,PR486,PR488,PR489,PR491,PR492,PR495,PR496,PR498,PR499,PR500,PR501,PR502,PR503,PR505,PR506,PR507,PR509,PR510,PR511,PR512,PR513,PR515,PR516,PR517,PR518,PR519,PR520,PR522,PR523,PR524,PR525,PR526,PR6555,PR6563,PR6624,PR6630",?,?,?,?
293,CS-2202FB01,RES CHIP 2.2 1/16W +-1%(0402)EF,CHIP,48,"PR79,PR80,PR87,PR88,PR94,PR99,PR100,PR107,PR108,PR131,PR132,PR185,PR186,PR193,PR194,PR201,PR205,PR206,PR213,PR256,PR257,PR264,PR265,PR271,PR276,PR277,PR318,PR319,PR326,PR327,PR344,PR345,PR352,PR356,PR357,PR364,PR370,PR371,PR416,PR422,PR427,PR430,PR6800,PR6801,PR8001,PR8002,PR8003,PR8004",?,Comp-Approve,End of Design,?
294,CS-2202JB25,RES CHIP 2.2 1/16W +-5%  (0402),CHIP,4,"PR6552,PR6560,PR6621,PR6627",?,Comp-Approve,End of Design,?
295,CS-5602FB01,RES CHIP 5.6 1/16W 1%(0402)EF,CHIP,46,"PR81,PR82,PR89,PR90,PR95,PR101,PR102,PR109,PR110,PR135,PR136,PR189,PR190,PR197,PR198,PR203,PR209,PR210,PR215,PR258,PR259,PR266,PR267,PR272,PR278,PR279,PR322,PR323,PR330,PR331,PR348,PR349,PR354,PR360,PR361,PR366,PR372,PR373,PR420,PR424,PR428,PR432,PR6554,PR6562,PR6623,PR6629",?,?,?,?
296,CS00001JE10,RES CHIP 0 1/20W +-5% (0201)EF,CHIP,111,"R595,R596,R597,R598,R599,R609,R611,R612,R613,R614,R615,R616,R619,R620,R621,R622,R697,R709,R711,R731,R732,R779,R780,R797,R799,R801,R802,R803,R805,R806,R807,R808,R809,R828,R829,R830,R831,R832,R833,R848,R850,R851,R854,R860,R872,R873,R895,R901,R913,R914,R953,R963,R976,R977,R1004,R1012,R1025,R1026,R1042,R1043,R1047,R1054,R1067,R1068,R1083,R1084,R1088,R1096,R1109,R1110,R1125,R1126,R1198,R1199,R1200,R1201,R1206,R1209,R1210,R1211,R1514,R1515,R6708,R6709,R6732,R6733,R6736,R6737,R6746,R6747,R6748,R6749,R6754,R6755,R6756,R6757,R6758,R6759,R6760,R6761,R6776,R6796,R6797,R6810,R6811,R6812,R6813,R6820,R6821,R6902,R6903",?,Comp-Approve,End of Design,?
297,CS00001JE10,RES CHIP 0 1/20W +-5% (0201)EF,CHIP,4,"R6152,R6153,R6156,R6157",?,Comp-Approve,End of Design,PCIE REDRIVER BOM1
298,CS00001JE10,RES CHIP 0 1/20W +-5% (0201)EF,CHIP,4,"R6154,R6155,R6158,R6159",?,Comp-Approve,End of Design,PCIE REDRIVER BOM2
299,CS00001JE10,RES CHIP 0 1/20W +-5% (0201)EF,CHIP,4,"R6190,R6191,R6194,R6195",?,Comp-Approve,End of Design,USB3_HUB1
300,CS00001JE10,RES CHIP 0 1/20W +-5% (0201)EF,CHIP,4,"R6192,R6193,R6196,R6197",?,Comp-Approve,End of Design,USB3_HUB2
301,CS00002JB13,RES CHIP 0 1/16W +-5%(0402)EF,CHIP,743,"PR12,PR13,PR14,PR32,PR33,PR34,PR35,PR36,PR37,PR40,PR59,PR60,PR62,PR68,PR69,PR74,PR83,PR84,PR91,PR92,PR96,PR103,PR104,PR111,PR112,PR121,PR125,PR137,PR138,PR150,PR169,PR170,PR172,PR173,PR174,PR181,PR191,PR192,PR199,PR200,PR204,PR211,PR212,PR216,PR217,PR236,PR237,PR239,PR245,PR246,PR251,PR260,PR261,PR268,PR269,PR273,PR280,PR281,PR283,PR302,PR303,PR305,PR306,PR307,PR314,PR324,PR325,PR332,PR333,PR335,PR340,PR350,PR351,PR355,PR362,PR363,PR367,PR374,PR375,PR384,PR387,PR388,PR397,PR398,PR401,PR406,PR407,PR408,PR409,PR411,PR412,PR415,PR417,PR419,PR421,PR425,PR429,PR433,PR435,PR436,PR437,PR440,PR441,PR442,PR445,PR477,PR530,PR531,PR532,PR533,PR832,PR835,PR3002,PR3337,PR6000,PR6500,PR6501,PR6520,PR6521,PR6531,PR6539,PR6540,PR6541,PR6542,PR6543,PR6544,PR6548,PR6550,PR6556,PR6564,PR6601,PR6603,PR6605,PR6606,PR6609,PR6610,PR6611,PR6612,PR6613,PR6614,PR6616,PR6618,PR6619,PR6626,PR6631,PR6809,PR6810,PR6811,PR6816,PR6819,PR6820,PR6821,PR8000,PR8005,PR8006,PR8007,PR8008,PR8009,PR8010,PR8011,PR8012,R9,R13,R14,R15,R27,R28,R29,R30,R38,R39,R40,R41,R42,R46,R51,R56,R57,R70,R74,R75,R76,R85,R86,R118,R119,R121,R122,R123,R125,R132,R133,R137,R141,R149,R151,R153,R156,R157,R162,R167,R168,R175,R180,R181,R182,R183,R184,R185,R187,R188,R189,R190,R193,R194,R196,R197,R198,R202,R203,R204,R205,R206,R209,R210,R211,R213,R222,R223,R226,R228,R230,R231,R233,R234,R235,R236,R237,R238,R239,R241,R242,R243,R244,R245,R246,R250,R251,R252,R253,R254,R255,R258,R260,R261,R262,R263,R264,R268,R269,R271,R274,R278,R280,R281,R283,R284,R286,R321,R325,R326,R327,R328,R333,R337,R338,R356,R357,R364,R374,R395,R404,R405,R407,R419,R426,R427,R428,R429,R430,R431,R435,R436,R439,R473,R474,R481,R482,R483,R484,R485,R486,R487,R493,R494,R529,R530,R564,R565,R566,R567,R570,R573,R576,R589,R600,R603,R606,R607,R618,R646,R647,R650,R651,R657,R658,R661,R662,R734,R744,R817,R818,R819,R856,R862,R877,R899,R905,R928,R929,R930,R931,R932,R934,R935,R936,R937,R939,R940,R955,R956,R1036,R1038,R1129,R1132,R1134,R1139,R1142,R1143,R1148,R1153,R1154,R1159,R1160,R1161,R1162,R1163,R1166,R1168,R1169,R1170,R1179,R1191,R1202,R1204,R1205,R1269,R1270,R1271,R1272,R1273,R1274,R1275,R1276,R1277,R1293,R1294,R1295,R1296,R1297,R1298,R1299,R1300,R1312,R1315,R1329,R1339,R1340,R1350,R1352,R1353,R1354,R1355,R1359,R1360,R1423,R1425,R1447,R1453,R1500,R1509,R1518,R1522,R1523,R1524,R1526,R1533,R1571,R1619,R1625,R1633,R1634,R1648,R1651,R1671,R1736,R1737,R1738,R1739,R1798,R1801,R1815,R1816,R1895,R2113,R2114,R2268,R2316,R2318,R2473,R2529,R2531,R2565,R2566,R2659,R2660,R2676,R2703,R2704,R2706,R2707,R2725,R2793,R2796,R2802,R2803,R2848,R2899,R2905,R2906,R2922,R2967,R2968,R2982,R2983,R2992,R3033,R3047,R3048,R3063,R3105,R3106,R3107,R3108,R3109,R3110,R3111,R3142,R3168,R3169,R3170,R3171,R3172,R3177,R3178,R3180,R3194,R3195,R3196,R3197,R3198,R3199,R3200,R3201,R3205,R3233,R3236,R3237,R3244,R3294,R3303,R3304,R3305,R3306,R3307,R3308,R3326,R3327,R3335,R3336,R3337,R3338,R3352,R3353,R3354,R3355,R3393,R3394,R3441,R3442,R3443,R3499,R3516,R3517,R3518,R3526,R3527,R3559,R3560,R3561,R3563,R3568,R3569,R3572,R3573,R3576,R3577,R3580,R3581,R3600,R3601,R3620,R3710,R3713,R3714,R3715,R3716,R3717,R3718,R3719,R3720,R3721,R3722,R3751,R3752,R3754,R3756,R3770,R3772,R3775,R3776,R3777,R3778,R3779,R3996,R4075,R4076,R4087,R4212,R4213,R4214,R4215,R4268,R4303,R4304,R4305,R4306,R4501,R4535,R4536,R4601,R4602,R4809,R5052,R5054,R5099,R5234,R5236,R5377,R6000,R6001,R6002,R6003,R6004,R6005,R6006,R6007,R6008,R6009,R6010,R6011,R6012,R6013,R6014,R6015,R6025,R6026,R6028,R6032,R6033,R6038,R6039,R6047,R6048,R6051,R6052,R6053,R6054,R6055,R6056,R6057,R6058,R6059,R6067,R6069,R6073,R6074,R6075,R6078,R6092,R6093,R6095,R6096,R6097,R6099,R6101,R6102,R6103,R6104,R6105,R6108,R6109,R6110,R6111,R6116,R6118,R6119,R6183,R6184,R6200,R6201,R6228,R6229,R6240,R6241,R6242,R6245,R6254,R6500,R6710,R6711,R6740,R6741,R6777,R6781,R6784,R6785,R6792,R6793,R6798,R6799,R6800,R6801,R6804,R6805,R6806,R6807,R6823,R6824,R6825,R6826,R6852,R6853,R6858,R6859,R8004,R8018,R8021,R8032,R8034,R8047,R8058,R8064,R8071,R8072,R8080,R8081,R8083,R8084,R8086,R8087,R8089,R8090,R8094,R8097,R8101,R8102,R8168,R8176,R8179,R8224,R8235,R8241,R8248,R8249,R8282,R8301,R8305,R8306,R8308,R8309,R8312,R8350,R8351,R8381,R8382,R8385,R8386,R8563,R8564,R8565,R8566,R9001,R9010,R9011,R9012,R9013,R9018,R9019,R9273,R9274,R9275,R9276",?,Comp-Approve,End of Design,?
302,CS00002JB13,RES CHIP 0 1/16W +-5%(0402)EF,EMPTY,146,"PR127,PR129,PR336,PR341,PR390,PR392,PR394,PR413,PR443,PR446,PR883,PR6551,PR6620,PR6802,PR6807,PR6808,R139,R140,R142,R143,R144,R145,R146,R147,R148,R150,R191,R192,R256,R257,R272,R323,R324,R358,R373,R490,R574,R575,R653,R664,R704,R789,R790,R852,R853,R857,R893,R894,R897,R941,R951,R952,R960,R986,R987,R988,R989,R990,R991,R1002,R1003,R1008,R1045,R1046,R1050,R1086,R1087,R1093,R1130,R1135,R1146,R1147,R1151,R1152,R1164,R1180,R1197,R1330,R1331,R1332,R1333,R1334,R1335,R1336,R1337,R1519,R1525,R2310,R2311,R2474,R2705,R2724,R2800,R2801,R2893,R2894,R2986,R2987,R3206,R3213,R3214,R3215,R3254,R3263,R3264,R3440,R3472,R3859,R3863,R3867,R3869,R3939,R3974,R4569,R4570,R4571,R4572,R4573,R4574,R4575,R4576,R4577,R4578,R5051,R6064,R6065,R6066,R6068,R6094,R6701,R6702,R6703,R8010,R8013,R8014,R8015,R8016,R8017,R8104,R8105,R8116,R8146,R8458,R9028,R9029,R9030",?,Comp-Approve,End of Design,?
303,CS00002JB13,RES CHIP 0 1/16W +-5%(0402)EF,CHIP,22,"PR2149,PR3910,PR3911,PR3916,PR3917,PR3919,PR3920,PR3921,PR3922,PR3928,PR3930,PR3980,PR3981,PR3988,PR3989,PR3992,PR3993,PR3994,PR3995,R1714,R2586,R3924",?,Comp-Approve,End of Design,HSC BOM1
304,CS00002JB13,RES CHIP 0 1/16W +-5%(0402)EF,CHIP,4,"PR4012,R3997,R4062,R8030",?,Comp-Approve,End of Design,SCM_P12V_MAM_BOM1
305,CS00002JB13,RES CHIP 0 1/16W +-5%(0402)EF,EMPTY,6,"R1136,R1182,R3794,R3832,R4060,R5487",?,Comp-Approve,End of Design,NIC_P3V3_BOM1
306,CS00002JB13,RES CHIP 0 1/16W +-5%(0402)EF,EMPTY,4,"R1137,R1196,R3631,R3845",?,Comp-Approve,End of Design,NIC_P3V3_BOM2
307,CS00002JB13,RES CHIP 0 1/16W +-5%(0402)EF,CHIP,8,"R561,R1181,R3144,R3784,R3827,R3831,R3868,R3870",?,Comp-Approve,End of Design,NIC_P12V_MAM_TIC_BOM1
308,CS00002JB13,RES CHIP 0 1/16W +-5%(0402)EF,CHIP,4,"R591,R1193,R3871,R3873",?,Comp-Approve,End of Design,NIC_P12V_MPS_MAM_BOM2
309,CS00002JB13,RES CHIP 0 1/16W +-5%(0402)EF,EMPTY,20,"R1227,R1228,R1245,R1246,R1247,R1248,R1249,R1250,R1258,R1260,R1792,R1793,R3679,R3681,R3683,R3685,R3687,R3860,R3864,R3940",?,Comp-Approve,End of Design,ADC_MAM_BOM2
310,CS00002JB13,RES CHIP 0 1/16W +-5%(0402)EF,CHIP,20,"R1243,R1244,R1251,R1252,R1254,R1255,R1256,R1257,R1259,R1263,R3671,R3672,R3680,R3682,R3684,R3686,R3688,R3861,R3865,R3941",?,Comp-Approve,End of Design,ADC_TI_BOM1
311,CS00002JB13,RES CHIP 0 1/16W +-5%(0402)EF,CHIP,4,"R1486,R1520,R3785,R3807",?,Comp-Approve,End of Design,NIC_P3V3_BOM1
312,CS00002JB13,RES CHIP 0 1/16W +-5%(0402)EF,CHIP,2,"R1487,R1521",?,Comp-Approve,End of Design,NIC_P3V3_BOM2
313,CS00002JB13,RES CHIP 0 1/16W +-5%(0402)EF,CHIP,5,"R353,R2626,R2627,R2628,R6210",?,Comp-Approve,End of Design,HSC BOM2
314,CS00002JB13,RES CHIP 0 1/16W +-5%(0402)EF,CHIP,7,"R2786,R2787,R3651,R3652,R3655,R3662,R3666",?,Comp-Approve,End of Design,USB2 BOM1
315,CS00002JB13,RES CHIP 0 1/16W +-5%(0402)EF,EMPTY,4,"R2788,R2789,R2790,R2791",?,Comp-Approve,End of Design,USB2 BOM2
316,CS00002JB13,RES CHIP 0 1/16W +-5%(0402)EF,EMPTY,2,"R3630,R3834",?,Comp-Approve,End of Design,NIC_P12V_MPS_MAM_BOM2
317,CS00002JB13,RES CHIP 0 1/16W +-5%(0402)EF,EMPTY,3,"R3862,R3866,R3942",?,Comp-Approve,End of Design,ADC_TI_BOM3
318,CS00002JB13,RES CHIP 0 1/16W +-5%(0402)EF,EMPTY,2,"R3872,R3874",?,Comp-Approve,End of Design,NIC_P12V_MPS_TIC_BOM3
319,CS00002JB13,RES CHIP 0 1/16W +-5%(0402)EF,CHIP,2,"R3943,R3955",?,Comp-Approve,End of Design,E1S_P12V_MPS_MAM_BOM2
320,CS00002JB13,RES CHIP 0 1/16W +-5%(0402)EF,CHIP,2,"R3946,R8100",?,Comp-Approve,End of Design,E1S_P3V3_BOM2
321,CS00002JB13,RES CHIP 0 1/16W +-5%(0402)EF,EMPTY,1,R3956,?,Comp-Approve,End of Design,E1S_P12V_MPS_TIC_BOM3
322,CS00002JB13,RES CHIP 0 1/16W +-5%(0402)EF,CHIP,4,"R3958,R3972,R3975,R4064",?,Comp-Approve,End of Design,E1S_P12V_MAM_TIC_BOM1
323,CS00002JB13,RES CHIP 0 1/16W +-5%(0402)EF,CHIP,3,"R3959,R3973,R4063",?,Comp-Approve,End of Design,E1S_P3V3_BOM1
324,CS00002JB13,RES CHIP 0 1/16W +-5%(0402)EF,CHIP,3,"R3998,R8012,R8031",?,Comp-Approve,End of Design,SCM_P12V_MPS_BOM2
325,CS00002JB13,RES CHIP 0 1/16W +-5%(0402)EF,EMPTY,2,"R4059,R4061",?,Comp-Approve,End of Design,NIC_P12V_MAM_TIC_BOM1
326,CS00002JB13,RES CHIP 0 1/16W +-5%(0402)EF,CHIP,1,R4450,?,Comp-Approve,End of Design,USB3_HUB1_CYP
327,CS00002JB13,RES CHIP 0 1/16W +-5%(0402)EF,CHIP,1,R4537,?,Comp-Approve,End of Design,PCIE REDRIVER BOM1
328,CS00002JB13,RES CHIP 0 1/16W +-5%(0402)EF,CHIP,1,R6162,?,Comp-Approve,End of Design,PCIE REDRIVER BOM2
329,CS00002JB13,RES CHIP 0 1/16W +-5%(0402)EF,EMPTY,2,"R6237,R6238",?,Comp-Approve,End of Design,HSC BOM2
330,CS00002JB13,RES CHIP 0 1/16W +-5%(0402)EF,CHIP,19,"R6259,R6261,R6263,R6264,R6266,R6268,R6270,R6271,R6276,R6286,R6291,R6296,R6300,R6305,R6311,R6314,R6317,R6322,R6324",?,Comp-Approve,End of Design,USB3_HUB2_MRP
331,CS00002JB13,RES CHIP 0 1/16W +-5%(0402)EF,CHIP,19,"R6260,R6262,R6265,R6267,R6269,R6274,R6275,R6279,R6280,R6285,R6290,R6295,R6299,R6304,R6310,R6313,R6316,R6323,R6328",?,Comp-Approve,End of Design,USB3_HUB2_TI
332,CS00006J900,RES CHIP 0 1/4W +-5%(0603),EMPTY,8,"R705,R858,R898,R961,R1010,R1051,R1094,R6704",?,?,?,?
333,CS00006J900,RES CHIP 0 1/4W +-5%(0603),CHIP,8,"R712,R859,R900,R962,R1011,R1053,R1095,R6705",?,?,?,?
334,CS0000FFT09,RES CHIP 0.0003 4W +-1%(2725)RLC,CHIP,4,"PR2532,PR2533,PR2534,PR6001",?,?,?,HSC BOM2
335,CS01002FB07,RES CHIP 10 1/16W +-1%(0402)EF,CHIP,16,"PR2514,PR2515,PR2516,PR2517,PR2518,PR2524,PR2525,PR2526,PR2527,PR2528,PR2529,PR2530,PR2531,PR2535,PR2536,PR2538",?,Comp-Approve,End of Design,HSC BOM2
336,CS01002FB07,RES CHIP 10 1/16W +-1%(0402)EF,EMPTY,1,PR2537,?,Comp-Approve,End of Design,HSC BOM2
337,CS01002FB07,RES CHIP 10 1/16W +-1%(0402)EF,CHIP,2,"PR3782,PR3798",?,Comp-Approve,End of Design,NIC_P3V3_BOM1
338,CS01002FB07,RES CHIP 10 1/16W +-1%(0402)EF,CHIP,2,"PR3792,PR3830",?,Comp-Approve,End of Design,NIC_P12V_MAM_TIC_BOM1
339,CS01002FB07,RES CHIP 10 1/16W +-1%(0402)EF,CHIP,1,PR3966,?,Comp-Approve,End of Design,E1S_P12V_MAM_TIC_BOM1
340,CS01002FB07,RES CHIP 10 1/16W +-1%(0402)EF,CHIP,1,PR3967,?,Comp-Approve,End of Design,E1S_P3V3_BOM1
341,CS01002FB07,RES CHIP 10 1/16W +-1%(0402)EF,CHIP,42,"PR400,PR434,R1283,R1284,R1291,R1292,R1301,R1302,R1674,R1675,R1676,R1677,R1678,R1679,R1680,R1681,R1683,R1684,R1685,R1686,R1687,R1696,R1697,R1699,R1701,R1704,R1705,R1707,R1708,R1709,R1710,R1711,R3570,R3571,R3574,R3575,R3578,R3579,R3602,R3603,R3758,R3760",?,Comp-Approve,End of Design,?
342,CS01002FB07,RES CHIP 10 1/16W +-1%(0402)EF,CHIP,1,PR4003,?,Comp-Approve,End of Design,SCM_P12V_MAM_BOM1
343,CS01002FB07,RES CHIP 10 1/16W +-1%(0402)EF,CHIP,1,R6284,?,Comp-Approve,End of Design,USB3_HUB2_TI
344,CS0100AFR00,RES CHIP 10 2W +-1%(2512),EMPTY,2,"R1480,R1481",?,?,?,?
345,CS01502FB03,RES CHIP 15 1/16W +-1%(0402)EF,CHIP,24,"R375,R376,R377,R378,R379,R380,R381,R382,R383,R384,R385,R386,R500,R501,R502,R503,R504,R505,R506,R507,R508,R509,R510,R511",?,Comp-Approve,End of Design,?
346,CS02201FE11,RES CHIP 22 1/20W +-1%(0201)EF,CHIP,2,"R674,R695",?,?,?,?
347,CS02202FB02,RES CHIP 22 1/16W +-1%(0402)EF,EMPTY,5,"R1290,R3209,R3210,R3211,R3212",?,Comp-Approve,End of Design,?
348,CS02202FB02,RES CHIP 22 1/16W +-1%(0402)EF,CHIP,17,"R59,R72,R73,R1635,R1636,R1638,R1639,R1640,R1641,R1642,R1643,R1644,R1645,R1740,R1741,R1742,R1743",?,Comp-Approve,End of Design,?
349,CS02202FB02,RES CHIP 22 1/16W +-1%(0402)EF,CHIP,2,"R2588,R3934",?,Comp-Approve,End of Design,HSC BOM1
350,CS02702JB02,RES CHIP 27 1/16W +-5%(0402)EF,CHIP,1,R2674,?,Comp-Approve,End of Design,?
351,CS02742FB03,RES CHIP 27.4 1/16W +-1%(0402)EF,CHIP,3,"R1140,R1141,R3181",?,Comp-Release Qty,End of Design,?
352,CS03302JB10,RES CHIP 33 1/16W +-5%(0402)EF,CHIP,173,"R23,R49,R50,R58,R63,R71,R81,R116,R120,R152,R158,R159,R160,R161,R163,R164,R165,R166,R169,R170,R171,R172,R173,R174,R176,R177,R179,R186,R195,R199,R208,R212,R214,R215,R216,R217,R218,R219,R220,R221,R224,R225,R227,R229,R232,R247,R248,R249,R259,R265,R266,R267,R270,R273,R275,R277,R279,R282,R285,R289,R308,R309,R349,R350,R351,R352,R371,R372,R434,R459,R460,R461,R463,R464,R466,R467,R468,R469,R470,R471,R475,R476,R477,R478,R488,R489,R497,R588,R602,R608,R645,R648,R685,R708,R738,R798,R933,R957,R958,R959,R992,R1005,R1203,R1253,R1278,R1279,R1280,R1281,R1282,R1311,R1321,R1362,R1363,R1458,R1459,R1494,R1495,R1496,R1497,R1498,R1528,R1549,R1550,R1551,R1552,R1553,R1556,R1557,R1558,R1563,R1564,R1592,R1593,R1616,R1620,R1631,R1632,R6029,R6030,R6031,R6063,R6076,R6077,R6506,R6782,R6783,R6850,R6851,R6854,R6855,R6856,R6857,R6862,R6863,R6864,R6865,R8005,R8006,R8007,R8008,R8057,R8066,R8073,R8166,R8177,R8178,R8234,R8243,R8250,R8299,R8310,R8311,R8383",?,Comp-Approve,End of Design,?
353,CS03302JB10,RES CHIP 33 1/16W +-5%(0402)EF,EMPTY,6,"R462,R472,R1155,R1156,R1157,R1158",?,Comp-Approve,End of Design,?
354,CS03321FE09,RES CHIP 33.2 1/20W +-1%(0201)EF,CHIP,17,"R668,R669,R672,R673,R678,R679,R682,R683,R687,R688,R689,R690,R693,R694,R698,R6779,R6780",?,?,?,?
355,CS03322FB03,RES CHIP 33.2 1/16W +-1%(0402)EF,CHIP,154,"R2,R55,R65,R347,R348,R604,R1173,R1174,R1175,R1177,R1178,R1344,R1345,R1346,R1347,R1348,R1349,R1516,R1517,R1594,R1595,R1719,R2261,R2262,R2410,R2411,R2413,R2414,R2415,R2416,R2417,R2418,R2419,R2420,R2421,R2422,R2423,R2424,R2425,R2489,R2663,R2664,R2671,R2672,R2675,R2811,R2812,R2844,R2845,R2846,R2847,R2897,R2898,R2939,R2944,R2990,R2991,R2995,R2996,R3036,R3066,R3112,R3113,R3114,R3185,R3191,R3193,R3203,R3231,R3234,R3238,R3239,R3301,R3315,R3324,R3340,R3341,R3397,R3476,R3477,R3478,R3479,R3480,R3481,R3482,R3483,R3484,R3485,R3486,R3496,R3497,R3505,R3533,R3534,R3553,R3554,R3586,R3587,R3588,R3589,R3590,R3591,R3592,R3593,R3594,R3595,R3654,R3711,R3712,R3858,R4143,R4144,R4145,R4146,R4147,R4148,R4149,R4150,R4151,R4152,R4157,R4170,R4171,R4172,R4178,R4179,R4180,R4181,R4182,R4183,R4266,R4506,R4507,R4508,R4509,R4556,R4557,R4558,R4563,R4608,R6112,R6113,R6252,R6253,R8000,R8118,R8124,R9022,R9023,R9031,R9033,R9034,R9446,R11667",?,Comp-Approve,End of Design,?
356,CS03322FB03,RES CHIP 33.2 1/16W +-1%(0402)EF,CHIP,1,R3909,?,Comp-Approve,End of Design,HSC BOM1
357,CS03322FB03,RES CHIP 33.2 1/16W +-1%(0402)EF,CHIP,1,R4451,?,Comp-Approve,End of Design,USB3_HUB1_CYP
358,CS03322FB03,RES CHIP 33.2 1/16W +-1%(0402)EF,EMPTY,2,"R6224,R6225",?,Comp-Approve,End of Design,USB3_HUB1_CYP
359,CS03322FB03,RES CHIP 33.2 1/16W +-1%(0402)EF,EMPTY,1,R8110,?,Comp-Approve,End of Design,HSC BOM2
360,CS04991FE06,RES CHIP 49.9 1/20W +-1%(0201)EF,EMPTY,6,"R339,R340,R343,R344,R345,R346",?,Comp-Approve,End of Design,?
361,CS04991FE06,RES CHIP 49.9 1/20W +-1%(0201)EF,CHIP,14,"R666,R667,R670,R671,R675,R676,R677,R680,R681,R684,R686,R691,R692,R696",?,Comp-Approve,End of Design,?
362,CS04992FB07,RES CHIP 49.9 1/16W +-1%(0402)EF,CHIP,73,"PR49,PR50,PR51,PR52,PR114,PR115,PR161,PR162,PR163,PR164,PR226,PR227,PR228,PR229,PR288,PR294,PR295,PR296,PR297,PR399,PR402,PR418,PR438,PR460,PR6530,PR6532,PR6600,PR6602,R1,R61,R315,R465,R605,R1568,R1569,R1570,R1572,R1573,R1574,R1575,R1576,R1577,R1578,R1579,R1580,R1581,R1582,R1583,R1584,R1585,R1586,R1587,R1588,R1589,R1590,R1591,R2917,R2924,R2925,R3390,R3391,R3392,R3468,R3469,R3515,R4550,R5102,R5103,R6100,R8171,R8182,R8238,R8304",?,Comp-Approve,End of Design,?
363,CS04992FB07,RES CHIP 49.9 1/16W +-1%(0402)EF,CHIP,2,"R2624,R2625",?,Comp-Approve,End of Design,HSC BOM2
364,CS04992FB07,RES CHIP 49.9 1/16W +-1%(0402)EF,EMPTY,4,"R4419,R4420,R4482,R4483",?,Comp-Approve,End of Design,?
365,CS04993F909,RES CHIP 49.9 1/10W +-1%(0603)EF,CHIP,2,"PR3843,PR3857",?,Comp-Approve,End of Design,NIC_P12V_MPS_MAM_BOM2
366,CS04993F909,RES CHIP 49.9 1/10W +-1%(0603)EF,CHIP,1,PR3957,?,Comp-Approve,End of Design,E1S_P12V_MPS_MAM_BOM2
367,CS04993F909,RES CHIP 49.9 1/10W +-1%(0603)EF,CHIP,1,PR4014,?,Comp-Approve,End of Design,SCM_P12V_MPS_BOM2
368,CS05102JB04,RES CHIP 51 1/16W +-5%(0402)EF,EMPTY,2,"R341,R342",?,Comp-Approve,End of Design,?
369,CS05111FE00,RES CHIP 51.1 1/20W +-1%(0201),EMPTY,16,"R623,R624,R625,R626,R627,R628,R629,R630,R631,R634,R635,R636,R637,R640,R641,R642",?,?,?,?
370,CS11002FB07,RES CHIP 100 1/16W +-1%(0402)EF,CHIP,1,PR2519,?,Comp-Approve,End of Design,HSC BOM2
371,CS11002FB07,RES CHIP 100 1/16W +-1%(0402)EF,EMPTY,2,"PR3838,PR3850",?,Comp-Approve,End of Design,NIC_P12V_MPS_MAM_BOM2
372,CS11002FB07,RES CHIP 100 1/16W +-1%(0402)EF,EMPTY,1,PR3950,?,Comp-Approve,End of Design,E1S_P12V_MPS_MAM_BOM2
373,CS11002FB07,RES CHIP 100 1/16W +-1%(0402)EF,EMPTY,1,PR4006,?,Comp-Approve,End of Design,SCM_P12V_MPS_BOM2
374,CS11002FB07,RES CHIP 100 1/16W +-1%(0402)EF,CHIP,16,"R22,R240,R1422,R1508,R1779,R1856,R1896,R1897,R1898,R3208,R3216,R3217,R5071,R6046,R6117,R8063",?,Comp-Approve,End of Design,?
375,CS11002FB07,RES CHIP 100 1/16W +-1%(0402)EF,EMPTY,4,"R733,R2426,R2656,R8019",?,Comp-Approve,End of Design,?
376,CS11302FB03,RES CHIP 130 1/16W +-1%(0402)EF,CHIP,21,"R948,R1444,R3069,R3071,R3074,R3075,R3086,R3087,R3088,R3089,R3090,R3091,R3092,R3093,R3094,R3095,R3096,R3097,R3099,R3100,R6246",?,Comp-Approve,End of Design,?
377,CS12001FE12,RES CHIP 200 1/20W +-1%(0201)EF,CHIP,16,"R701,R756,R869,R910,R973,R1022,R1041,R1064,R1082,R1106,R1124,R6723,R6731,R6795,R6809,R6901",?,?,?,?
378,CS12002FB06,RES CHIP 200 1/16W +-1%(0402)EF,CHIP,6,"R47,R48,R1194,R1266,R3228,R3229",?,Comp-Approve,End of Design,?
379,CS12002FB06,RES CHIP 200 1/16W +-1%(0402)EF,CHIP,1,R6202,?,Comp-Approve,End of Design,USB3_HUB1_CYP
380,CS12436F201,RES CHIP 243 1/4W +-1%(1206)EF,CHIP,4,"R4638,R4639,R4640,R4641",?,?,?,?
381,CS12492FB02,RES CHIP 249 1/16W +-1%(0402)EF,CHIP,2,"R950,R8029",?,Comp-Approve,End of Design,?
382,CS14702FB04,RES CHIP 470 1/16W +-1%(0402)EF,CHIP,3,"R1207,R1208,R3102",?,Comp-Approve,End of Design,?
383,CS14993F901,RES CHIP 499 1/10W +-1%(0603)EF,CHIP,2,"PR6557,PR6625",?,Comp-Approve,End of Design,?
384,CS15602FB03,RES CHIP 560 1/16W +-1%(0402)EF,CHIP,6,"R8022,R8023,R8024,R8025,R8026,R8027",?,?,?,?
385,CS16802FB03,RES CHIP 680 1/16W +-1%(0402)EF,CHIP,1,R3653,?,?,?,USB2 BOM1
386,CS16812FB02,RES CHIP 681 1/16W +-1%(0402)EF,CHIP,1,PR292,?,Comp-Approve,End of Design,?
387,CS18452FB01,RES CHIP 845 1/16W +-1%(0402)EF,CHIP,2,"PR3781,PR3823",?,Comp-Approve,End of Design,NIC_P12V_MAM_TIC_BOM1
388,CS21001FE07,RES CHIP 1K 1/20W +-1%(0201)EF,CHIP,88,"R735,R796,R810,R812,R826,R827,R834,R835,R836,R837,R838,R839,R840,R841,R861,R892,R902,R949,R964,R969,R1013,R1018,R1044,R1055,R1060,R1085,R1097,R1102,R1127,R1212,R1213,R1214,R1215,R1216,R1217,R1218,R1219,R1364,R1372,R1380,R1391,R1400,R1408,R1410,R1411,R1415,R1416,R1418,R1420,R1428,R1429,R1431,R1432,R1436,R1437,R1448,R1451,R1462,R1463,R1468,R1469,R6706,R6707,R6712,R6717,R6718,R6719,R6734,R6735,R6738,R6739,R6750,R6751,R6752,R6753,R6762,R6763,R6764,R6765,R6766,R6767,R6768,R6769,R6788,R6789,R6790,R6791,R6822",?,?,?,?
389,CS21001FE07,RES CHIP 1K 1/20W +-1%(0201)EF,EMPTY,48,"R699,R741,R745,R795,R863,R864,R887,R903,R904,R927,R965,R966,R968,R1014,R1015,R1017,R1040,R1056,R1057,R1059,R1081,R1098,R1099,R1101,R1123,R1369,R1377,R1388,R1397,R1405,R1413,R1426,R1434,R1445,R1456,R1466,R1472,R1478,R1484,R1490,R1512,R6713,R6714,R6716,R6730,R6794,R6808,R6900",?,?,?,?
390,CS21002FB06,RES CHIP 1K 1/16W +-1%(0402)EF,EMPTY,147,"PR41,PR128,PR151,PR218,PR284,PR391,PR6607,PR6803,PR6804,PR6805,PR6806,PR6813,PR6817,PR6818,R21,R64,R68,R88,R89,R90,R91,R92,R93,R94,R95,R96,R97,R98,R99,R100,R101,R102,R103,R104,R105,R106,R107,R108,R109,R110,R111,R112,R113,R114,R115,R124,R127,R128,R129,R154,R155,R290,R322,R420,R421,R423,R425,R541,R542,R543,R556,R557,R563,R610,R643,R656,R722,R1049,R1052,R1264,R1326,R1327,R1328,R1529,R1530,R1531,R1532,R1655,R2222,R2233,R2693,R2695,R4184,R4186,R4188,R4190,R4192,R4194,R4196,R4198,R4200,R4202,R4204,R4206,R4620,R5006,R5007,R5008,R5009,R5010,R5011,R5012,R5013,R5014,R5015,R5016,R5017,R5018,R5019,R5020,R5021,R5053,R6121,R6122,R6123,R6124,R6125,R6131,R6132,R6133,R6137,R6138,R6139,R6140,R6141,R6147,R6148,R6149,R6742,R6743,R8011,R8042,R8043,R8045,R8048,R8153,R8156,R8160,R8219,R8220,R8222,R8225,R8286,R8287,R8289,R8293,R9021",?,Comp-Approve,End of Design,?
391,CS21002FB06,RES CHIP 1K 1/16W +-1%(0402)EF,CHIP,217,"PR55,PR152,PR232,PR285,PR334,PR337,PR339,PR342,PR378,PR395,PR403,PR410,PR414,PR439,PR444,PR447,PR836,PR6615,PR6812,PR8073,R44,R54,R62,R87,R117,R178,R291,R292,R293,R294,R295,R296,R297,R298,R299,R300,R301,R302,R303,R304,R305,R306,R307,R310,R311,R312,R313,R314,R317,R319,R359,R360,R362,R363,R366,R367,R369,R370,R398,R399,R400,R401,R402,R403,R442,R443,R523,R524,R525,R526,R527,R528,R569,R587,R601,R638,R639,R652,R655,R659,R663,R665,R710,R714,R718,R747,R811,R993,R1128,R1131,R1133,R1144,R1149,R1165,R1167,R1171,R1183,R1184,R1185,R1186,R1187,R1188,R1189,R1190,R1192,R1303,R1507,R1527,R1546,R1605,R1621,R1624,R1626,R1627,R1628,R1629,R1630,R1646,R1647,R1649,R1650,R1654,R1775,R1776,R1777,R1854,R1905,R1906,R1907,R1908,R2694,R2696,R2950,R3133,R3134,R3135,R3136,R3147,R3173,R3176,R3322,R3454,R3459,R3470,R3488,R3490,R3704,R3707,R3709,R4090,R4091,R4092,R4093,R4094,R4185,R4187,R4189,R4191,R4193,R4195,R4197,R4199,R4201,R4203,R4205,R4207,R4521,R4543,R4605,R6034,R6120,R6126,R6127,R6128,R6129,R6130,R6134,R6135,R6136,R6142,R6143,R6144,R6145,R6146,R6150,R6151,R6744,R6745,R6786,R6787,R6860,R6861,R8033,R8056,R8065,R8070,R8075,R8106,R8119,R8125,R8165,R8167,R8180,R8184,R8233,R8242,R8247,R8252,R8298,R8300,R8313,R8317,R8380,R8420,R8423,R9000,R10296",?,Comp-Approve,End of Design,?
392,CS21002FB06,RES CHIP 1K 1/16W +-1%(0402)EF,EMPTY,1,PR3929,?,Comp-Approve,End of Design,HSC BOM1
393,CS21002FB06,RES CHIP 1K 1/16W +-1%(0402)EF,EMPTY,4,"R1239,R1241,R3667,R3669",?,Comp-Approve,End of Design,ADC_TI_BOM1
394,CS21002FB06,RES CHIP 1K 1/16W +-1%(0402)EF,CHIP,4,"R1240,R1242,R3668,R3670",?,Comp-Approve,End of Design,ADC_TI_BOM1
395,CS21002FB06,RES CHIP 1K 1/16W +-1%(0402)EF,CHIP,2,"R2587,R3925",?,Comp-Approve,End of Design,HSC BOM1
396,CS21002FB06,RES CHIP 1K 1/16W +-1%(0402)EF,EMPTY,14,"R3269,R3270,R3271,R3272,R3275,R3276,R3277,R3280,R3281,R3283,R3286,R3287,R3289,R3290",?,Comp-Approve,End of Design,PCIE REDRIVER BOM1
397,CS21002FB06,RES CHIP 1K 1/16W +-1%(0402)EF,CHIP,2,"R3278,R3284",?,Comp-Approve,End of Design,PCIE REDRIVER BOM1
398,CS21002FB06,RES CHIP 1K 1/16W +-1%(0402)EF,CHIP,7,"R6160,R6164,R6168,R6170,R6172,R6177,R6179",?,Comp-Approve,End of Design,PCIE REDRIVER BOM2
399,CS21002FB06,RES CHIP 1K 1/16W +-1%(0402)EF,EMPTY,12,"R6163,R6165,R6166,R6167,R6169,R6171,R6173,R6174,R6175,R6176,R6178,R6180",?,Comp-Approve,End of Design,PCIE REDRIVER BOM2
400,CS21002FB06,RES CHIP 1K 1/16W +-1%(0402)EF,CHIP,1,R6223,?,Comp-Approve,End of Design,USB3_HUB1_CYP
401,CS21002FB06,RES CHIP 1K 1/16W +-1%(0402)EF,EMPTY,5,"R6281,R6282,R6283,R6288,R6292",?,Comp-Approve,End of Design,USB3_HUB2_TI
402,CS21002FB06,RES CHIP 1K 1/16W +-1%(0402)EF,CHIP,1,R6287,?,Comp-Approve,End of Design,USB3_HUB2_TI
403,CS21002FB06,RES CHIP 1K 1/16W +-1%(0402)EF,EMPTY,1,R9020,?,Comp-Approve,End of Design,HSC BOM2
404,CS21212FB05,RES CHIP 1.21K 1/16W +-1%(0402)EF,CHIP,1,R1800,?,Comp-Approve,End of Design,?
405,CS21332FB05,RES CHIP 1.33K 1/16W +-1%(0402)EF,CHIP,2,"PR3846,PR3856",?,?,?,NIC_P3V3_BOM2
406,CS21332FB05,RES CHIP 1.33K 1/16W +-1%(0402)EF,CHIP,1,PR4008,?,?,?,SCM_P12V_MAM_BOM1
407,CS21502FB07,RES CHIP 1.5K 1/16W +-1%(0402)EF,EMPTY,1,PR833,?,Comp-Approve,End of Design,?
408,CS21962FB05,RES CHIP 1.96K 1/16W +-1%(0402)EF,CHIP,1,PR67,?,?,?,?
409,CS22002BB07,RES CHIP 2K 1/16W +-0.1%(0402)EF,CHIP,10,"PR1101,PR1131,PR1133,PR3914,PR3915,PR3918,PR3986,PR3987,PR3990,PR3991",?,?,?,HSC BOM1
410,CS22002FB07,RES CHIP 2K 1/16W +-1%(0402)EF,EMPTY,9,"R329,R1007,R1319,R1384,R1385,R1386,R3062,R6036,R6037",?,Comp-Approve,End of Design,?
411,CS22002FB07,RES CHIP 2K 1/16W +-1%(0402)EF,CHIP,5,"R3,R1230,R2900,R6114,R6115",?,Comp-Approve,End of Design,?
412,CS22002JB29,RES CHIP 2K(1/16W +-5% 0402),EMPTY,8,"R6016,R6017,R6018,R6019,R6020,R6021,R6022,R6023",?,Comp-Approve,End of Design,?
413,CS22202JB07,RES CHIP 2.2K 1/16W +-5%(0402)EF,CHIP,82,"R66,R67,R207,R387,R388,R389,R390,R391,R393,R394,R396,R397,R408,R409,R410,R411,R412,R413,R414,R415,R416,R417,R418,R422,R424,R437,R441,R498,R512,R513,R514,R515,R516,R517,R518,R520,R521,R522,R531,R532,R533,R534,R535,R537,R538,R539,R540,R559,R562,R632,R633,R1089,R1090,R1316,R1341,R1351,R1357,R1424,R2667,R2669,R2984,R2985,R3395,R3396,R3535,R3536,R3582,R3583,R3723,R3724,R3725,R3726,R3727,R3728,R3729,R3730,R3731,R3732,R6211,R6212,R6502,R6503",?,Comp-Approve,End of Design,?
414,CS22202JB07,RES CHIP 2.2K 1/16W +-5%(0402)EF,EMPTY,21,"R330,R331,R332,R392,R519,R536,R1460,R2204,R2205,R2212,R2213,R2999,R3004,R3226,R3227,R3240,R3241,R3242,R3243,R4269,R4270",?,Comp-Approve,End of Design,?
415,CS22202JB07,RES CHIP 2.2K 1/16W +-5%(0402)EF,CHIP,2,"R6230,R6231",?,Comp-Approve,End of Design,HSC BOM2
416,CS22492FB05,RES CHIP 2.49K 1/16W +-1%(0402)EF,CHIP,1,PR3969,?,Comp-Approve,End of Design,E1S_P3V3_BOM1
417,CS22672FB03,RES CHIP 2.67K 1/16W +-1%(0402)EF,CHIP,1,PR3970,?,Comp-Approve,End of Design,E1S_P12V_MAM_TIC_BOM1
418,CS22802FB04,RES CHIP 2.8K 1/16W +-1%(0402)EF,CHIP,1,PR3947,?,Comp-Approve,End of Design,E1S_P3V3_BOM2
419,CS23092FB04,RES CHIP 3.09K 1/16W +-1%(0402)EF,CHIP,1,PR126,?,?,?,?
420,CS23902JB04,RES CHIP 3.9K 1/16W +-5%(0402)EF,EMPTY,1,R5238,?,Comp-Approve,End of Design,USB2 BOM2
421,CS24532FB03,RES CHIP 4.53K 1/16W +-1%(0402)EF,CHIP,2,"PR3824,PR5481",?,Comp-Approve,End of Design,NIC_P3V3_BOM1
422,CS24701JE04,RES CHIP 4.7K 1/20W +-5%(0201)EF,EMPTY,94,"R706,R716,R720,R724,R728,R755,R758,R759,R781,R784,R786,R788,R794,R842,R843,R844,R868,R870,R871,R874,R878,R880,R882,R886,R909,R911,R912,R915,R918,R920,R922,R926,R972,R974,R975,R978,R981,R983,R985,R1001,R1006,R1021,R1023,R1024,R1027,R1030,R1032,R1034,R1048,R1063,R1065,R1066,R1069,R1073,R1075,R1077,R1091,R1105,R1107,R1108,R1111,R1114,R1116,R1119,R1438,R1439,R1446,R1454,R1455,R1461,R1464,R1465,R1467,R1470,R1471,R1473,R1476,R1477,R1479,R1482,R1483,R1485,R1488,R1489,R1499,R1510,R1511,R1513,R6722,R6724,R6725,R6770,R6771,R6772",?,Comp-Approve,End of Design,?
423,CS24701JE04,RES CHIP 4.7K 1/20W +-5%(0201)EF,CHIP,78,"R719,R723,R725,R726,R727,R785,R787,R791,R792,R793,R845,R846,R847,R879,R881,R883,R884,R885,R919,R921,R923,R924,R925,R982,R984,R995,R997,R998,R1031,R1033,R1035,R1037,R1039,R1074,R1076,R1078,R1079,R1080,R1115,R1118,R1120,R1121,R1122,R1361,R1365,R1366,R1367,R1368,R1371,R1373,R1374,R1375,R1376,R1379,R1381,R1382,R1383,R1387,R1390,R1392,R1393,R1394,R1395,R1399,R1401,R1402,R1403,R1404,R1407,R1409,R1412,R1417,R1421,R1430,R1433,R6773,R6774,R6775",?,Comp-Approve,End of Design,?
424,CS24702FB06,RES CHIP 4.7K 1/16W +-1%(0402)EF,CHIP,27,"R32,R34,R53,R1224,R1308,R1320,R1322,R1785,R2488,R2843,R3162,R3167,R3184,R3190,R3295,R3296,R3608,R3611,R3616,R3622,R3623,R3624,R3627,R3763,R4568,R6247,R6250",?,Comp-Approve,End of Design,?
425,CS24702FB06,RES CHIP 4.7K 1/16W +-1%(0402)EF,EMPTY,4,"R1267,R1268,R3689,R3690",?,Comp-Approve,End of Design,ADC_TI_BOM1
426,CS24702FB06,RES CHIP 4.7K 1/16W +-1%(0402)EF,EMPTY,26,"R31,R33,R138,R649,R660,R1305,R1306,R1307,R1309,R1310,R1317,R2487,R3163,R3166,R3192,R3609,R3610,R3612,R3613,R3617,R3621,R3628,R3764,R4514,R6251,R9044",?,Comp-Approve,End of Design,?
427,CS24702FB06,RES CHIP 4.7K 1/16W +-1%(0402)EF,EMPTY,3,"R3265,R3291,R3293",?,Comp-Approve,End of Design,PCIE REDRIVER BOM1
428,CS24702FB06,RES CHIP 4.7K 1/16W +-1%(0402)EF,CHIP,2,"R3266,R3292",?,Comp-Approve,End of Design,PCIE REDRIVER BOM1
429,CS24702FB06,RES CHIP 4.7K 1/16W +-1%(0402)EF,CHIP,1,R3936,?,Comp-Approve,End of Design,HSC BOM1
430,CS24702FB06,RES CHIP 4.7K 1/16W +-1%(0402)EF,CHIP,2,"R6293,R6306",?,Comp-Approve,End of Design,USB3_HUB2_TI
431,CS24702FB06,RES CHIP 4.7K 1/16W +-1%(0402)EF,EMPTY,1,R6307,?,Comp-Approve,End of Design,USB3_HUB2_TI
432,CS24702FB06,RES CHIP 4.7K 1/16W +-1%(0402)EF,CHIP,2,"R6326,R6330",?,Comp-Approve,End of Design,USB3_HUB2_MRP
433,CS24702FB06,RES CHIP 4.7K 1/16W +-1%(0402)EF,EMPTY,1,R6327,?,Comp-Approve,End of Design,USB3_HUB2_MRP
434,CS24702JB10,RES CHIP 4.7K 1/16W +-5%(0402)EF,CHIP,113,"R276,R444,R445,R446,R447,R450,R451,R452,R492,R495,R499,R544,R545,R546,R547,R550,R551,R552,R553,R590,R617,R654,R938,R942,R943,R944,R945,R946,R947,R996,R999,R1000,R1285,R1286,R1287,R1288,R1313,R1318,R1338,R1356,R1419,R1547,R1567,R1622,R1637,R1658,R1702,R1703,R1729,R2121,R2125,R2344,R2530,R2794,R2834,R2835,R2836,R2841,R2842,R2909,R2915,R2918,R2926,R2932,R2937,R3029,R3034,R3320,R3432,R3433,R3434,R3435,R3474,R3500,R3501,R3503,R3519,R3520,R3530,R3532,R4125,R4126,R4127,R4137,R4138,R4139,R4155,R4164,R4165,R4166,R4264,R4545,R4553,R4560,R4604,R6081,R6082,R6083,R6084,R6090,R6181,R6182,R8002,R8003,R8028,R9004,R9005,R9008,R9009,R9016,R9017,R9026,R9043",?,Comp-Approve,End of Design,?
435,CS24702JB10,RES CHIP 4.7K 1/16W +-5%(0402)EF,EMPTY,76,"R4,R24,R26,R43,R78,R134,R135,R200,R201,R287,R288,R361,R365,R368,R406,R438,R440,R448,R449,R455,R456,R457,R491,R548,R549,R558,R581,R582,R583,R584,R757,R1071,R1195,R1314,R1343,R1659,R1730,R2668,R2670,R2805,R2807,R2820,R2911,R2912,R2914,R2916,R2923,R2940,R2946,R2948,R3317,R3448,R3451,R3506,R3773,R4265,R4549,R4555,R5026,R5027,R5028,R5029,R5030,R5031,R5032,R6024,R6027,R6035,R6061,R6062,R6070,R6071,R6186,R6188,R8035,R8036",?,Comp-Approve,End of Design,?
436,CS24702JB10,RES CHIP 4.7K 1/16W +-5%(0402)EF,EMPTY,2,"R4066,R4069",?,Comp-Approve,End of Design,NIC_P3V3_BOM1
437,CS24702JB10,RES CHIP 4.7K 1/16W +-5%(0402)EF,CHIP,1,R4073,?,Comp-Approve,End of Design,E1S_P12V_MAM_TIC_BOM1
438,CS24702JB10,RES CHIP 4.7K 1/16W +-5%(0402)EF,EMPTY,2,"R6045,R6060",?,Comp-Approve,End of Design,NIC_P12V_MAM_TIC_BOM1
439,CS24702JB10,RES CHIP 4.7K 1/16W +-5%(0402)EF,CHIP,1,R6049,?,Comp-Approve,End of Design,E1S_P3V3_BOM1
440,CS24702JB10,RES CHIP 4.7K 1/16W +-5%(0402)EF,EMPTY,1,R6258,?,Comp-Approve,End of Design,USB3_HUB2_TI
441,CS24752FB03,RES CHIP 4.75K 1/16W +-1%(0402)EF,CHIP,2,"R579,R4489",?,Comp-Approve,End of Design,?
442,CS24752FB03,RES CHIP 4.75K 1/16W +-1%(0402)EF,EMPTY,2,"R578,R4490",?,Comp-Approve,End of Design,?
443,CS24872FB01,RES CHIP 4.87K 1/16W +-1%(0402)EF,EMPTY,2,"PR133,PR134",?,Comp-Approve,End of Design,?
444,CS24872FB07,RES CHIP 4.87K 1/16W+-1%(0402),EMPTY,2,"PR328,PR329",?,Comp-Approve,End of Design,?
445,CS24992BB04,RES CHIP 4.99K 1/16W +-0.1%(0402)EF,CHIP,2,"PR3927,PR3932",?,?,?,HSC BOM1
446,CS24992FB07,RES CHIP 4.99K 1/16W +-1%(0402)EF,EMPTY,6,"PR599,PR600,PR601,PR602,PR603,PR604",?,Comp-Approve,End of Design,?
447,CS25112FB04,RES CHIP 5.11K 1/16W +-1%(0402)EF,CHIP,12,"R1231,R1232,R1233,R1234,R1235,R1236,R1237,R2907,R2908,R4567,R8115,R8122",?,Comp-Approve,End of Design,?
448,CS25232FB08,RES CHIP 5.23K 1/16W +-1%(0402)EF,CHIP,1,PR159,?,?,?,?
449,CS25362FB02,RES CHIP 5.36K 1/16W +-1%(0402)EF,CHIP,2,"PR3780,PR3822",?,Comp-Approve,End of Design,NIC_P3V3_BOM1
450,CS25362FB02,RES CHIP 5.36K 1/16W +-1%(0402)EF,EMPTY,2,"PR885,PR6604",?,Comp-Approve,End of Design,?
451,CS26042FB04,RES CHIP 6.04K 1/16W +-1%(0402)EF,CHIP,1,R6203,?,Comp-Approve,End of Design,USB3_HUB1_CYP
452,CS26192FB03,RES CHIP 6.19K 1/16W +-1%(0402)EF,CHIP,1,R1117,?,Comp-Approve,End of Design,HSC BOM1
453,CS26802FB02,RES CHIP 6.8K 1/16W +-1%(0402)EF,CHIP,2,"PR3787,PR3806",?,?,?,NIC_P12V_MAM_TIC_BOM1
454,CS26802FB02,RES CHIP 6.8K 1/16W +-1%(0402)EF,CHIP,1,PR3961,?,?,?,E1S_P12V_MAM_TIC_BOM1
455,CS26802FB02,RES CHIP 6.8K 1/16W +-1%(0402)EF,CHIP,1,PR4001,?,?,?,SCM_P12V_MAM_BOM1
456,CS26982FB08,RES CHIP 6.98K 1/16W +-1%(0402)EF,CHIP,1,PR452,?,?,?,?
457,CS27152FB03,RES CHIP 7.15K 1/16W +-1%(0402)EF,CHIP,2,"PR3790,PR3829",?,Comp-Approve,End of Design,NIC_P3V3_BOM1
458,CS27152FB03,RES CHIP 7.15K 1/16W +-1%(0402)EF,CHIP,1,PR3964,?,Comp-Approve,End of Design,E1S_P3V3_BOM1
459,CS27152FB03,RES CHIP 7.15K 1/16W +-1%(0402)EF,CHIP,2,"PR6502,PR6522",?,Comp-Approve,End of Design,?
460,CS27872FB02,RES CHIP 7.87K 1/16W +-1%(0402)EF,CHIP,1,R1799,?,Comp-Approve,End of Design,?
461,CS28452FB06,RES CHIP 8.45K 1/16W +-1%( 0402)EF,EMPTY,1,R8103,?,?,?,?
462,CS28662FB02,RES CHIP 8.66K 1/16W +-1%(0402)EF,CHIP,2,"PR8,PR448",?,Comp-Approve,End of Design,?
463,CS28872FB01,RES CHIP 8.87K 1/16W +-1%(0402)EF,EMPTY,42,"PR7,PR77,PR78,PR85,PR86,PR93,PR97,PR98,PR105,PR106,PR187,PR188,PR195,PR196,PR202,PR207,PR208,PR214,PR254,PR255,PR262,PR263,PR270,PR274,PR275,PR320,PR321,PR346,PR347,PR353,PR358,PR359,PR365,PR368,PR369,PR423,PR426,PR431,PR6553,PR6561,PR6622,PR6628",?,Comp-Approve,End of Design,?
464,CS29092FB05,RES CHIP 9.09K 1/16W +-1%(0402)EF,CHIP,2,"R1226,R1791",?,Comp-Approve,End of Design,?
465,CS29312FB02,RES CHIP 9.31K 1/16W +-1%(0402)EF,CHIP,1,PR3968,?,Comp-Approve,End of Design,E1S_P12V_MAM_TIC_BOM1
466,CS29532FB06,RES CHIP 9.53K 1/16W +-1%(0402)EF,CHIP,1,PR244,?,?,?,?
467,CS29532FB06,RES CHIP 9.53K 1/16W +-1%(0402)EF,CHIP,1,R6331,?,?,?,USB3_HUB2_TI
468,CS29762FB05,RES CHIP 9.76K 1/16W +-1%(0402)EF,CHIP,1,PR3971,?,Comp-Approve,End of Design,E1S_P3V3_BOM1
469,CS31001FE17,RES CHIP 10K 1/20W +-1%(0201)EF,CHIP,42,"R707,R715,R749,R752,R782,R783,R849,R866,R867,R875,R876,R907,R908,R916,R917,R970,R971,R979,R980,R1019,R1020,R1028,R1029,R1061,R1062,R1070,R1072,R1103,R1104,R1112,R1113,R1370,R1378,R1389,R1398,R1406,R1414,R1427,R1435,R6720,R6721,R6778",?,?,?,?
470,CS31002FB08,RES CHIP 10K 1/16W +-1%(0402)EF,CHIP,119,"PR3,PR4,PR5,PR6,PR54,PR147,PR231,PR470,PR6003,PR6008,PR6010,PR6011,PR6507,PR6526,R7,R10,R11,R12,R16,R17,R18,R19,R20,R25,R35,R36,R37,R45,R69,R126,R335,R479,R560,R568,R577,R580,R585,R592,R593,R594,R721,R800,R804,R994,R1009,R1138,R1150,R1176,R1304,R1342,R1396,R1673,R1734,R1744,R1745,R1746,R1747,R1822,R1824,R1857,R1929,R1930,R2317,R2356,R2666,R3164,R3165,R3174,R3175,R3182,R3183,R3297,R3298,R3455,R3457,R3465,R3466,R3467,R3487,R3507,R3509,R3529,R3660,R3771,R4058,R4079,R4080,R4081,R4121,R4135,R4153,R4476,R4491,R4492,R4518,R4519,R4520,R4603,R5004,R6085,R6185,R6243,R6244,R6504,R6802,R6803,R8037,R8038,R8039,R8040,R8113,R8120,R8421,R8422,R9002,R9006,R9014,R9032,R10287",?,Comp-Approve,End of Design,?
471,CS31002FB08,RES CHIP 10K 1/16W +-1%(0402)EF,CHIP,2,"PR2106,PR3935",?,Comp-Approve,End of Design,HSC BOM1
472,CS31002FB08,RES CHIP 10K 1/16W +-1%(0402)EF,CHIP,6,"PR3839,PR3842,PR3851,PR3854,R3848,R4532",?,Comp-Approve,End of Design,NIC_P12V_MPS_MAM_BOM2
473,CS31002FB08,RES CHIP 10K 1/16W +-1%(0402)EF,CHIP,3,"PR3951,PR3954,R3948",?,Comp-Approve,End of Design,E1S_P12V_MPS_MAM_BOM2
474,CS31002FB08,RES CHIP 10K 1/16W +-1%(0402)EF,CHIP,3,"PR4007,PR4011,R3836",?,Comp-Approve,End of Design,SCM_P12V_MPS_BOM2
475,CS31002FB08,RES CHIP 10K 1/16W +-1%(0402)EF,EMPTY,38,"PR6814,PR6815,R52,R60,R136,R316,R318,R320,R496,R713,R717,R1474,R1475,R1727,R1728,R1731,R1735,R1748,R2227,R2230,R2343,R2921,R3471,R3703,R3705,R3706,R3708,R4078,R4082,R6086,R6087,R6088,R6089,R6187,R8082,R8085,R8088,R8091",?,Comp-Approve,End of Design,?
476,CS31002FB08,RES CHIP 10K 1/16W +-1%(0402)EF,EMPTY,5,"R3656,R3657,R3658,R3659,R3664",?,Comp-Approve,End of Design,USB2 BOM1
477,CS31002FB08,RES CHIP 10K 1/16W +-1%(0402)EF,CHIP,1,R3663,?,Comp-Approve,End of Design,USB2 BOM1
478,CS31002FB08,RES CHIP 10K 1/16W +-1%(0402)EF,CHIP,2,"R4065,R4068",?,Comp-Approve,End of Design,NIC_P12V_MAM_TIC_BOM1
479,CS31002FB08,RES CHIP 10K 1/16W +-1%(0402)EF,CHIP,2,"R4067,R4070",?,Comp-Approve,End of Design,NIC_P3V3_BOM1
480,CS31002FB08,RES CHIP 10K 1/16W +-1%(0402)EF,CHIP,1,R4071,?,Comp-Approve,End of Design,SCM_P12V_MAM_BOM1
481,CS31002FB08,RES CHIP 10K 1/16W +-1%(0402)EF,CHIP,1,R4072,?,Comp-Approve,End of Design,E1S_P3V3_BOM1
482,CS31002FB08,RES CHIP 10K 1/16W +-1%(0402)EF,CHIP,1,R4074,?,Comp-Approve,End of Design,E1S_P12V_MAM_TIC_BOM1
483,CS31002FB08,RES CHIP 10K 1/16W +-1%(0402)EF,EMPTY,8,"R4452,R6214,R6216,R6217,R6218,R6220,R6226,R6227",?,Comp-Approve,End of Design,USB3_HUB1_CYP
484,CS31002FB08,RES CHIP 10K 1/16W +-1%(0402)EF,CHIP,11,"R6204,R6205,R6206,R6207,R6208,R6209,R6213,R6215,R6219,R6221,R6222",?,Comp-Approve,End of Design,USB3_HUB1_CYP
485,CS31002FB08,RES CHIP 10K 1/16W +-1%(0402)EF,EMPTY,6,"R6233,R6235,R6236,R8107,R8109,R8111",?,Comp-Approve,End of Design,HSC BOM2
486,CS31002FB08,RES CHIP 10K 1/16W +-1%(0402)EF,CHIP,1,R6239,?,Comp-Approve,End of Design,HSC BOM2
487,CS31002FB08,RES CHIP 10K 1/16W +-1%(0402)EF,EMPTY,3,"R6277,R6278,R6320",?,Comp-Approve,End of Design,USB3_HUB2_MRP
488,CS31002FB08,RES CHIP 10K 1/16W +-1%(0402)EF,CHIP,3,"R6289,R6294,R6298",?,Comp-Approve,End of Design,USB3_HUB2_MRP
489,CS31002FB08,RES CHIP 10K 1/16W +-1%(0402)EF,CHIP,6,"R6297,R6301,R6312,R6315,R6319,R6325",?,Comp-Approve,End of Design,USB3_HUB2_TI
490,CS31002FB08,RES CHIP 10K 1/16W +-1%(0402)EF,EMPTY,1,R6329,?,Comp-Approve,End of Design,USB3_HUB2_TI
491,CS31002JB08,RES CHIP 10K 1/16W +-5%(0402)EF,EMPTY,28,"R130,R702,R703,R729,R736,R739,R740,R742,R748,R754,R814,R815,R820,R823,R825,R888,R889,R890,R891,R1145,R1172,R1358,R1491,R1501,R5056,R6098,R8092,R8095",?,Comp-Approve,End of Design,?
492,CS31002JB08,RES CHIP 10K 1/16W +-5%(0402)EF,CHIP,35,"R131,R453,R454,R644,R730,R737,R743,R751,R753,R760,R813,R816,R821,R822,R824,R1261,R1262,R1265,R1449,R1450,R1452,R1457,R1492,R1493,R1502,R5055,R5101,R6040,R6042,R6044,R6106,R6107,R6505,R8009,R8465",?,Comp-Approve,End of Design,?
493,CS31002JB08,RES CHIP 10K 1/16W +-5%(0402)EF,EMPTY,1,R8098,?,Comp-Approve,End of Design,E1S_P3V3_BOM2
494,CS31052FB03,RES CHIP 10.5K 1/16W +-1%(0402)EF,CHIP,2,"R354,R355",?,?,?,HSC BOM2
495,CS31152FB03,RES CHIP 11.5K 1/16W +-1%(0402)EF,CHIP,1,PR6004,?,Comp-Approve,End of Design,?
496,CS31152FB03,RES CHIP 11.5K 1/16W +-1%(0402)EF,EMPTY,2,"R855,R954",?,Comp-Approve,End of Design,?
497,CS31182BB06,RES CHIP 11.8K 1/16W +-0.1%(0402)EF,CHIP,1,PR8091,?,?,?,?
498,CS31202FB04,RES CHIP 12K 1/16W +-1%(0402)EF,CHIP,1,R6332,?,Comp-Approve,End of Design,USB3_HUB2_MRP
499,CS31242FB02,RES CHIP 12.4K 1/16W +-1%(0402)EF,CHIP,1,PR454,?,Comp-Approve,End of Design,?
500,CS31372FB03,RES CHIP 13.7K 1/16W +-1%(0402)EF,CHIP,1,PR464,?,Comp-Approve,End of Design,?
501,CS31432FB02,RES CHIP 14.3K 1/16W +-1%(0402)EF,CHIP,2,"PR3835,PR3847",?,Comp-Approve,End of Design,NIC_P12V_MPS_MAM_BOM2
502,CS31502BB03,RES CHIP 15K  1/16W +-0.1%(0402)EF,CHIP,1,PR830,?,Comp-Approve,End of Design,?
503,CS31502FB05,RES CHIP 15K 1/16W +-1%(0402)EF,CHIP,2,"PR3788,PR3828",?,Comp-Approve,End of Design,NIC_P12V_MAM_TIC_BOM1
504,CS31502FB05,RES CHIP 15K 1/16W +-1%(0402)EF,CHIP,2,"PR3791,PR3812",?,Comp-Approve,End of Design,NIC_P3V3_BOM1
505,CS31502FB05,RES CHIP 15K 1/16W +-1%(0402)EF,CHIP,1,PR3962,?,Comp-Approve,End of Design,E1S_P12V_MAM_TIC_BOM1
506,CS31502FB05,RES CHIP 15K 1/16W +-1%(0402)EF,CHIP,1,PR3965,?,Comp-Approve,End of Design,E1S_P3V3_BOM1
507,CS31502FB05,RES CHIP 15K 1/16W +-1%(0402)EF,CHIP,1,PR4002,?,Comp-Approve,End of Design,SCM_P12V_MAM_BOM1
508,CS31542FB02,RES CHIP 15.4K 1/16W +-1%(0402)EF,CHIP,4,"R761,R765,R770,R774",?,?,?,?
509,CS31692FB03,RES CHIP 16.9K 1/16W +-1%(0402)EF,CHIP,3,"PR8089,R1441,R1443",?,Comp-Approve,End of Design,?
510,CS31692FB03,RES CHIP 16.9K 1/16W +-1%(0402)EF,CHIP,1,R3933,?,Comp-Approve,End of Design,HSC BOM1
511,CS31742FB04,RES CHIP 17.4K 1/16W +-1%(0402)EF,CHIP,2,"PR3837,PR3849",?,Comp-Approve,End of Design,NIC_P12V_MPS_MAM_BOM2
512,CS31782FB04,RES CHIP 17.8K 1/16W +- 1% (0402)EF,CHIP,1,PR4004,?,Comp-Approve,End of Design,SCM_P12V_MAM_BOM1
513,CS31782FB04,RES CHIP 17.8K 1/16W +- 1% (0402)EF,CHIP,2,"R8114,R8121",?,Comp-Approve,End of Design,?
514,CS31802FB04,RES CHIP 18K 1/16W +-1%(0402)EF,CHIP,8,"R1220,R1221,R1222,R1223,R1225,R1229,R1238,R3005",?,?,?,?
515,CS32001FE00,RES CHIP 20K 1/20W +-1%(0201),CHIP,8,"R746,R865,R906,R967,R1016,R1058,R1100,R6715",?,?,?,?
516,CS32002FB06,RES CHIP 20K 1/16W +-1%(0402)EF,CHIP,5,"PR148,PR471,PR6007,PR6505,PR6524",?,Comp-Approve,End of Design,?
517,CS32002FB06,RES CHIP 20K 1/16W +-1%(0402)EF,CHIP,1,PR4540,?,Comp-Approve,End of Design,SCM_P12V_MPS_BOM2
518,CS32002FB06,RES CHIP 20K 1/16W +-1%(0402)EF,CHIP,1,PR4541,?,Comp-Approve,End of Design,E1S_P12V_MPS_MAM_BOM2
519,CS32152FB04,RES CHIP 21.5K 1/16W +-1%(0402)EF,CHIP,1,PR834,?,?,?,?
520,CS32212FB02,RES CHIP 22.1K 1/16W +-1%(0402)EF,CHIP,1,PR6533,?,Comp-Approve,End of Design,?
521,CS32322FB03,RES CHIP 23.2K 1/16W +-1%(0402)EF,CHIP,4,"R762,R766,R771,R775",?,Comp-Approve,End of Design,?
522,CS32432FB03,RES CHIP 24.3K 1/16W +-1%(0402)EF,CHIP,1,PR3999,?,?,?,SCM_P12V_MPS_BOM2
523,CS32552FB06,RES CHIP 25.5K 1/16W +-1%(0402)EF,CHIP,2,"PR3789,PR3795",?,Comp-Approve,End of Design,NIC_P3V3_BOM1
524,CS32552FB06,RES CHIP 25.5K 1/16W +-1%(0402)EF,CHIP,1,PR3963,?,Comp-Approve,End of Design,E1S_P3V3_BOM1
525,CS32672FB03,RES CHIP 26.7K 1/16W +-1%(0402)EF,EMPTY,1,R2221,?,Comp-Approve,End of Design,?
526,CS33002FB02,RES CHIP 30K 1/16W +-1%(0402)EF,CHIP,5,"R750,R1503,R1504,R1505,R1506",?,Comp-Approve,End of Design,?
527,CS33002FB02,RES CHIP 30K 1/16W +-1%(0402)EF,EMPTY,3,"R458,R700,R896",?,Comp-Approve,End of Design,?
528,CS33012FB03,RES CHIP 30.1K 1/16W +-1%(0402)EF,CHIP,2,"PR3821,PR5484",?,Comp-Approve,End of Design,NIC_P12V_MAM_TIC_BOM1
529,CS33012FB03,RES CHIP 30.1K 1/16W +-1%(0402)EF,CHIP,1,PR4005,?,Comp-Approve,End of Design,SCM_P12V_MPS_BOM2
530,CS33162FB02,RES CHIP 31.6K 1/16W +-1%(0402)EF,CHIP,1,R2585,?,Comp-Approve,End of Design,?
531,CS33302FB00,RES CHIP 33K 1/16W +-1%(0402)EF,CHIP,1,R3907,?,?,?,?
532,CS33572FB01,RES CHIP 35.7K 1/16W +-1%(0402) EF,CHIP,4,"R763,R767,R772,R776",?,Comp-Approve,End of Design,?
533,CS34022FB04,RES CHIP 40.2K 1/16W +-1%(0402)EF,CHIP,6,"PR53,PR113,PR157,PR230,PR290,PR376",?,Comp-Approve,End of Design,?
534,CS34642FB02,RES CHIP 46.4K 1/16W +-1%(0402)EF,CHIP,1,PR3944,?,?,?,E1S_P12V_MPS_MAM_BOM2
535,CS34702BB05,RES CHIP 47K 1/16W +-0.1%(0402)EF,CHIP,1,PR831,?,?,?,?
536,CS34702BB05,RES CHIP 47K 1/16W +-0.1%(0402)EF,EMPTY,1,R3661,?,?,?,?
537,CS34702BB05,RES CHIP 47K 1/16W +-0.1%(0402)EF,EMPTY,1,R4453,?,?,?,USB3_HUB1_CYP
538,CS34702BB05,RES CHIP 47K 1/16W +-0.1%(0402)EF,EMPTY,1,R6321,?,?,?,USB3_HUB2_MRP
539,CS34702BB05,RES CHIP 47K 1/16W +-0.1%(0402)EF,EMPTY,1,R6333,?,?,?,USB3_HUB2_TI
540,CS35492FB03,RES CHIP 54.9K 1/16W  +-1%(0402)EF,CHIP,20,"R5,R6,R768,R777,R3461,R3463,R3464,R3492,R3494,R3498,R3508,R3510,R3511,R3513,R3514,R3521,R3522,R3523,R3524,R3525",?,Comp-Approve,End of Design,?
541,CS35492FB03,RES CHIP 54.9K 1/16W  +-1%(0402)EF,EMPTY,8,"R4119,R4123,R4131,R4133,R4158,R4160,R4162,R4551",?,Comp-Approve,End of Design,?
542,CS35492FB03,RES CHIP 54.9K 1/16W  +-1%(0402)EF,CHIP,1,R9024,?,Comp-Approve,End of Design,HSC BOM2
543,CS35602FB00,RES CHIP 56K 1/16W +-1%(0402)EF,CHIP,1,PR3949,?,?,?,E1S_P12V_MPS_MAM_BOM2
544,CS35602FB00,RES CHIP 56K 1/16W +-1%(0402)EF,CHIP,1,PR455,?,?,?,?
545,CS36042FB04,RES CHIP 60.4K 1/16W +-1%(0402)EF,CHIP,2,"PR6005,PR6006",?,Comp-Approve,End of Design,?
546,CS36342FB04,RES CHIP 63.4K 1/16W +-1%(0402)EF,CHIP,1,R3923,?,Comp-Approve,End of Design,?
547,CS36802FB04,RES CHIP 68K 1/16W +-1%(0402)EF,EMPTY,8,"R3267,R3268,R3273,R3274,R3279,R3282,R3285,R3288",?,Comp-Approve,End of Design,PCIE REDRIVER BOM1
548,CS37152FB05,RES CHIP 71.5K 1/16W +-1%(0402)EF,EMPTY,2,"PR3840,PR3852",?,?,?,NIC_P12V_MPS_MAM_BOM2
549,CS37152FB05,RES CHIP 71.5K 1/16W +-1%(0402)EF,CHIP,2,"PR3844,PR3855",?,?,?,NIC_P3V3_BOM2
550,CS37152FB05,RES CHIP 71.5K 1/16W +-1%(0402)EF,CHIP,1,PR3945,?,?,?,E1S_P3V3_BOM2
551,CS37152FB05,RES CHIP 71.5K 1/16W +-1%(0402)EF,EMPTY,1,PR3952,?,?,?,E1S_P12V_MPS_MAM_BOM2
552,CS37152FB05,RES CHIP 71.5K 1/16W +-1%(0402)EF,EMPTY,1,PR4009,?,?,?,SCM_P12V_MPS_BOM2
553,CS37502BB01,RES CHIP 75K 1/16W +-0.1%(0402)EF,CHIP,2,"PR3926,PR3931",?,?,?,HSC BOM1
554,CS38202FB01,RES CHIP 82K  1/16W +-1% (0402)EF,CHIP,1,R4901,?,Comp-Approve,End of Design,?
555,CS38452FB05,RES CHIP 84.5K 1/16W +-1%(0402)EF,CHIP,4,"R764,R769,R773,R778",?,Comp-Approve,End of Design,?
556,CS38662FB05,RES CHIP 86.6K 1/16W +-1%(0402)EF,CHIP,1,PR8092,?,Comp-Approve,End of Design,?
557,CS38662FB05,RES CHIP 86.6K 1/16W +-1%(0402)EF,EMPTY,1,R3118,?,Comp-Approve,End of Design,?
558,CS39092FB04,RES CHIP 90.9K 1/16W +-1%(0402)EF,CHIP,1,R6318,?,Comp-Approve,End of Design,USB3_HUB2_TI
559,CS41002FB09,RES CHIP 100K 1/16W +-1%(0402)EF,CHIP,65,"R8,R77,R79,R80,R82,R83,R84,R334,R336,R480,R554,R1289,R1440,R1442,R2346,R2528,R2828,R2830,R2832,R2838,R2919,R2920,R2927,R2933,R2934,R2935,R2941,R3030,R3035,R3132,R3207,R3232,R3235,R3321,R3436,R3437,R3438,R3439,R3449,R3452,R3475,R3504,R4128,R4129,R4130,R4140,R4141,R4142,R4156,R4167,R4168,R4169,R4515,R4548,R4552,R4554,R4559,R4561,R6041,R6043,R6501,R8093,R8096,R8413,R9027",?,Comp-Approve,End of Design,?
560,CS41002FB09,RES CHIP 100K 1/16W +-1%(0402)EF,EMPTY,46,"R2815,R2829,R2831,R2833,R2837,R2910,R2936,R3028,R3032,R3318,R3428,R3429,R3430,R3431,R3453,R3456,R3460,R3462,R3473,R3489,R3491,R3493,R3495,R3502,R3512,R4120,R4122,R4124,R4132,R4134,R4136,R4154,R4159,R4161,R4163,R4173,R4544,R4546,R4547,R4562,R6050,R8001,R9003,R9007,R9015,R9025",?,Comp-Approve,End of Design,?
561,CS41002FB09,RES CHIP 100K 1/16W +-1%(0402)EF,CHIP,1,R3665,?,Comp-Approve,End of Design,USB2 BOM1
562,CS41002FB09,RES CHIP 100K 1/16W +-1%(0402)EF,EMPTY,2,"R3783,R3826",?,Comp-Approve,End of Design,NIC_P3V3_BOM1
563,CS41002FB09,RES CHIP 100K 1/16W +-1%(0402)EF,CHIP,2,"R3796,R3833",?,Comp-Approve,End of Design,NIC_P3V3_BOM1
564,CS41002FB09,RES CHIP 100K 1/16W +-1%(0402)EF,CHIP,4,"R3797,R3799,R3816,R3825",?,Comp-Approve,End of Design,NIC_P12V_MAM_TIC_BOM1
565,CS41002FB09,RES CHIP 100K 1/16W +-1%(0402)EF,CHIP,2,"R3976,R3978",?,Comp-Approve,End of Design,E1S_P12V_MAM_TIC_BOM1
566,CS41002FB09,RES CHIP 100K 1/16W +-1%(0402)EF,CHIP,2,"R3977,R3979",?,Comp-Approve,End of Design,E1S_P3V3_BOM1
567,CS41002FB09,RES CHIP 100K 1/16W +-1%(0402)EF,CHIP,2,"R4013,R4015",?,Comp-Approve,End of Design,SCM_P12V_MAM_BOM1
568,CS41002FB09,RES CHIP 100K 1/16W +-1%(0402)EF,CHIP,1,R8099,?,Comp-Approve,End of Design,E1S_P3V3_BOM2
569,CS41202FB05,RES CHIP 120K 1/16W +-1%(0402)EF,CHIP,5,"PR1134,PR3912,PR3937,PR3982,PR3984",?,?,?,HSC BOM1
570,CS41202FB05,RES CHIP 120K 1/16W +-1%(0402)EF,CHIP,2,"PR3841,PR3853",?,?,?,NIC_P12V_MPS_MAM_BOM2
571,CS41202FB05,RES CHIP 120K 1/16W +-1%(0402)EF,CHIP,1,PR3953,?,?,?,E1S_P12V_MPS_MAM_BOM2
572,CS41202FB05,RES CHIP 120K 1/16W +-1%(0402)EF,CHIP,1,PR4010,?,?,?,SCM_P12V_MPS_BOM2
573,CS41602FB05,RES CHIP 160K 1/16W+-1%(0402)EF,CHIP,2,"PR3786,PR3805",?,?,?,NIC_P12V_MAM_TIC_BOM1
574,CS41602FB05,RES CHIP 160K 1/16W+-1%(0402)EF,CHIP,1,PR3960,?,?,?,E1S_P12V_MAM_TIC_BOM1
575,CS41602FB05,RES CHIP 160K 1/16W+-1%(0402)EF,CHIP,1,PR4000,?,?,?,SCM_P12V_MAM_BOM1
576,CS41602FB05,RES CHIP 160K 1/16W+-1%(0402)EF,EMPTY,3,"R6232,R6234,R8108",?,?,?,HSC BOM2
577,CS42002FB05,RES CHIP 200K 1/16W +-1%(0402)EF,CHIP,2,"R1700,R4211",?,Comp-Approve,End of Design,?
578,CS42002FB05,RES CHIP 200K 1/16W +-1%(0402)EF,EMPTY,5,"R2476,R3531,R4208,R4209,R4210",?,Comp-Approve,End of Design,?
579,CS42002FB05,RES CHIP 200K 1/16W +-1%(0402)EF,CHIP,3,"R6272,R6302,R6309",?,Comp-Approve,End of Design,USB3_HUB2_MRP
580,CS42002FB05,RES CHIP 200K 1/16W +-1%(0402)EF,EMPTY,3,"R6273,R6303,R6308",?,Comp-Approve,End of Design,USB3_HUB2_MRP
581,CS42672FB03,RES CHIP 267K 1/16W +-1%(0402)EF,EMPTY,1,R2219,?,Comp-Approve,End of Design,?
582,CS45102JB03,RES CHIP 510K 1/16W +-5%(0402)EF,EMPTY,1,R3117,?,Comp-Approve,End of Design,?
583,CS51002FB05,RES CHIP 1M 1/16W +-1%(0402)EF,CHIP,1,R6257,?,Comp-Approve,End of Design,USB3_HUB2
584,CS51002FB05,RES CHIP 1M 1/16W +-1%(0402)EF,EMPTY,1,R8112,?,Comp-Approve,End of Design,HSC BOM2
585,CS51002FB05,RES CHIP 1M 1/16W +-1%(0402)EF,CHIP,2,"R8117,R8123",?,Comp-Approve,End of Design,?
586,CS61002FB02,RES CHIP 10M 1/16W +-1%(0402)EF,CHIP,2,"PR4522,PR4524",?,?,?,NIC_P12V_MAM_TIC_BOM1
587,CS61002FB02,RES CHIP 10M 1/16W +-1%(0402)EF,CHIP,2,"PR4523,PR4525",?,?,?,NIC_P3V3_BOM1
588,CS61002FB02,RES CHIP 10M 1/16W +-1%(0402)EF,CHIP,1,PR4526,?,?,?,SCM_P12V_MAM_BOM1
589,CS61002FB02,RES CHIP 10M 1/16W +-1%(0402)EF,CHIP,1,PR4527,?,?,?,E1S_P3V3_BOM1
590,CS61002FB02,RES CHIP 10M 1/16W +-1%(0402)EF,CHIP,1,PR4528,?,?,?,E1S_P12V_MAM_TIC_BOM1
591,CS61002FB02,RES CHIP 10M 1/16W +-1%(0402)EF,EMPTY,1,R1092,?,?,?,?
592,CS61002FB02,RES CHIP 10M 1/16W +-1%(0402)EF,CHIP,2,"R432,R571",?,?,?,?
593,CS62002FB01,RES CHIP 20M 1/16W +-1%(0402)EF,CHIP,2,"R433,R572",?,?,?,?
594,CV+10G0MZ04,IND SMD 100NH 20% 16A(HCBS4545-101),IND,15,"L4,L6,L8,L10,L12,L14,L21,L23,PL24,PL56,PL6500,PL6503,PL6504,PL6510,PL8045",?,?,?,?
595,CV+12^0EZ03,IND SMD 120NH 15% 69A(PGL6312.121AHLT),IND,8,"PL9,PL27,PL39,PL50,PL6505,PL6506,PL6511,PL6512",?,?,?,?
596,CV+15^0TZ04,IND SMD 150NH 15% 82A(PGL6303.151HLT),IND,38,"PL7,PL8,PL10,PL11,PL13,PL14,PL15,PL17,PL18,PL20,PL21,PL28,PL29,PL31,PL32,PL33,PL35,PL36,PL38,PL40,PL41,PL43,PL44,PL45,PL47,PL48,PL51,PL52,PL59,PL60,PL61,PL63,PL64,PL66,PL67,PL68,PL69,PL70",?,Comp-Approve,End of Design,?
597,CV+22Y0EZ00,IND SMD 0.22UH 15% 33A(HCME656510Q-221QL,IND,4,"PL16,PL34,PL46,PL62",?,?,?,?
598,CV-10I0MZ01,IND SMD 1.0UH +-20% 18A(PCMC104T-1R0MN),IND,2,"PL57,PL78",?,?,?,?
599,CV-10U0MZ01,IND SMD 1UH +-20% 29A(PCMC135T-1R0MF),IND,2,"PL6501,PL6502",?,?,?,?
600,CV-15I0MZ28,IND SMD 1.5UH+-20% 18A(PCMC063T-1R5MN),IND,1,PL72,?,?,?,?
601,CV-15^0MZ02,IND SMD 1.5UH 20% 53A(EM-15AM17VG1-QS),IND,1,PL8066,?,?,?,?
602,CV-2280MZ15,IND SMD 2.2UH +-20% 8A(PCMC063T-2R2MN),IND,1,PL6001,?,?,?,?
603,CV-3360MZ07,"IND SMD 3.3UH,6A20%(PCMC063T-3R3MN)",IND,1,PL6000,?,?,?,?
604,CV-47A0MZ10,IND SMD 4.7UH +-20% 10A(PCMB104E-4R7MS),IND,1,PL8065,?,?,?,?
605,CVA50^0MZ09,IND SMD 50NH 20% 86A(PG2292.500HLT),IND,8,"PL12,PL19,PL30,PL37,PL42,PL49,PL53,PL65",?,Comp-Approve,End of Design,?
606,CVA90^0KZ13,IND SMD 90NH 10% 155A(PG2323.900HLT),IND,4,"PL22,PL23,PL54,PL55",?,Comp-Approve,End of Design,?
607,CX1PG221001,EMI FILTER BLM21PG221SN1D(220.100M.2A),IND,2,"L6000,L6001",?,Comp-Approve,End of Design,USB3_HUB1_CYP
608,CX1PG221001,EMI FILTER BLM21PG221SN1D(220.100M.2A),IND,2,"L6003,L6004",?,Comp-Approve,End of Design,USB3_HUB2
609,CX220TN1001,"EMI FILTER BLM18SN220TN1D(22,8000MA)",IND,6,"PL26,PL71,PL77,PL6002,PL6003,PL8064",?,Comp-Approve,End of Design,?
610,CX300SN1000,"EMI FILTER BLM21SN300SN1D(30,8.5A)",IND,8,"L3,L5,L7,L9,L11,L13,L18,L22",?,?,?,?
611,CX5PD121000,"EMI FILTER BLM15PD121SN1D(120OHM,1300MA)",IND,8,"L26,L27,L28,L29,L30,L31,L32,L33",?,?,?,?
612,CX601T05003,"EMI FILTER FCM2012KF-601T05(600,0.5A)",IND,5,"L1,L2,L17,L19,L20",?,?,?,?
613,CX8PG300001,"EMI FILTER SBK160808T-100Y-N(10,500MA)",IND,2,"L15,L24",?,?,?,?
614,CX8PG300001,"EMI FILTER SBK160808T-100Y-N(10,500MA)",IND,2,"L16,L25",?,?,?,ADC_TI_BOM1
615,DFHD03MS213,"CONN DIP HEADER 3P 1R MS(P2.54,H8.6)",IO,7,"JP10,JP12,JP4003,JP6000,JP6001,JP6500,PJ1",?,?,?,?
616,DFHD04MS460,"CONN DIP HEADER 4P 1R MS(P2,H6)",IO,2,"J8,J13",?,?,?,?
617,DFHD06MS263,"CONN DIP HEADER 6P 2R MS(P2.54,H8.38)",IO,1,J6,?,?,?,?
618,DFHD08MS197,"CONN DIP HEADER 8P 1R MS(P2.54,H8.38)",IO,1,J57,?,?,?,?
619,DFHD08MS385,"CONN SMD HEADER 8P 2R MS(P1.27,H5.5)",IO,4,"J5,J7,J48,J49",?,?,?,?
620,DFHD10MS117,"CONN DIP HEADER 10P 2R MS(P2.54, H8.38)",IO,1,J212,?,?,?,?
621,DFHD20MS153,"CONN SMD HEADER 20P 2R MS(P1.27,H6.14)",IO,1,J54,?,?,?,?
622,DFHD60MR024,"CONN DIP HEADER 60P 4R MR(P2.54,H12.57)",IO,1,J45,?,?,?,?
623,DFHS02FR062,"CONN DIP HOUSING 2P 1R FR(P20,H8.80)",IO,1,BT2,?,?,?,?
624,DFHS03FR030,CONN DIP HOUSING 3P 1R FR(H14.7),IO,2,"J122,J123",?,?,?,?
625,DFHS21FS003,"CONN SMD HOUSING 21P 2R FS(P1,H3.28)",IO,1,PJ38,?,?,?,HSC BOM2
626,DFHS56FS022,"CONN SMD HOUSING 56P 2R FS(P0.6, H9.25)",IO,1,J90,?,?,?,?
627,DFHS75FR313,"CONN SMD HOUSING 75P 2R FR(P0.5,H6.7)",EMPTY,1,J59,?,?,?,?
628,DFHSB2FR012,"CONN DIP HOUSING 112P 8R FR(P1.2,H17.9)",IO,7,"J105,J106,J107,J108,J109,J110,J111",?,?,?,?
629,DFHSG0FR007,"CONN DIP HOUSING 160P 8R FR(P1.2,H25.1)",IO,1,J112,?,?,?,?
630,DFHSG8FR011,"CONN SMD HOUSING 168P 2R FR(P0.6,H5.35)",IO,3,"J35,J38,J41",?,?,?,?
631,DFHST8FS479,"CONN SMD HS DDR5 288P 2R FS(P0.85,H21.3)",IO,24,"J1,J15,J16,J17,J18,J19,J20,J21,J23,J24,J26,J27,J28,J29,J30,J32,J33,J37,J67,J68,J69,J99,J100,J102",?,?,?,?
632,DGA^6000030,"SOCKET SP5 6096P LGA(P0.94,H4)",IO,2,"U25,U26",?,?,?,?
633,DHD00010F01,SWITCH SMD DIP(DHNF-10F-Q-T/R),MECH,1,SW1,?,?,?,?
634,DKK00XFU000,"FUSE SMD 20A/125V(FAST,UL/CSA)",IC,1,FS1,?,?,?,?
635,DUMMY1,QUANTA_LOGO_7X26,EMPTY,1,ME1,?,?,?,?
636,DUMMY2,WEEE,EMPTY,1,ME2,?,?,?,?
637,DUMMY28_HCLU2002010,"EFI BIOS LABEL LU2(HCLU2002,REV3A)",EMPTY,1,ME17,?,?,?,?
638,DUMMY3,PB-E1_SMALL,EMPTY,1,ME3,?,?,?,?
639,DUMMY36,SNLABEL_15X5,EMPTY,1,ME29,?,?,?,?
640,DUMMY46,SNLABEL_27X6,EMPTY,1,ME4,?,?,?,?
641,DUMMY47,CBS_3MMX558-8MM,EMPTY,1,ME5,?,?,?,?
642,DUMMY48,PICKUP_SMDC20,EMPTY,10,"ME7,ME8,ME9,ME10,ME11,ME12,ME13,ME14,ME15,ME16",?,?,?,?
643,DUMMY50,HOLE_TOOLINGD125N_T2-0,EMPTY,4,"H27,H28,H29,H30",?,?,?,?
644,DUMMY7,PCB_VENDOR_LOGO_15X8,EMPTY,1,ME6,?,?,?,?
645,GND_HOLE140,GNDHOLE_8PIN_C10D5-5B10,EMPTY,2,"H113,H114",?,?,?,?
646,GND_HOLE514,GND_C10D6-5B10_NPM_RB_NSP,EMPTY,1,H115,?,?,?,?
647,HOLE1187,HOLE_R4-2X5D2B4_IX0-1T_NPM_RB,EMPTY,2,"H76,H77",?,?,?,?
648,HOLE1195,HOLE_C8D4-2B8_NPB,EMPTY,1,H6002,?,?,?,?
649,HOLE1226,HOLE_C6-2D3-73B6-2I5-53_RO6-53_NPB,EMPTY,24,"H2,H3,H5,H8,H10,H11,H12,H13,H21,H22,H33,H34,H37,H38,H43,H44,H49,H50,H53,H54,H6000,H6001,H8027,H8028",?,?,?,?
650,HOLE1247,HOLE_OB6-4X8OBD3-2X4-8B6-4X8N_RO6X7-6_NPM,EMPTY,2,"H74,H75",?,?,?,?
651,HOLE1248,HOLE_C4-5D3-8B8I5-6_RO6-6_NPT_RB,EMPTY,2,"H31,H32",?,?,?,?
652,HOLE372,HOLE_C5D3-1N,EMPTY,1,H90,?,?,?,?
653,HOLE596,HOLE_C10D5-6B10_NPB,EMPTY,21,"H86,H87,H88,H89,H91,H92,H93,H94,H95,H96,H97,H98,H99,H100,H101,H102,H103,H104,H105,H106,H128",?,?,?,?
654,N_A,"(USE SYM_2)TDR 3PIN,2X141MIL 1X100MIL P2P",EMPTY,16,"DB1,DB2,DB3,DB4,DB5,DB6,DB7,DB8,DB9,DB10,DB11,DB12,DB13,DB14,DB15,DB16",?,?,?,?
655,N_A,DIFF_TEST_PAD DIP FOR FTS ONLY,EMPTY,44,"X1,X2,X3,X4,X5,X6,X7,X8,X9,X10,X11,X12,X25,X26,X27,X28,X8001,X8002,X8003,X8004,X8005,X8006,X8007,X8008,X8009,X8010,X8011,X8012,X8025,X8026,X8027,X8028,X9002,X9003,X9004,X9005,X9008,X9009,X9010,X9011,X9025,X9026,X9027,X9028",?,?,?,?
656,SHORT16,SHORT_10X12_M_FOR_INNER_LAYER,EMPTY,4,"PJ09_P0_N,PJ09_P0_P,PJ09_P1_N,PJ09_P1_P",?,?,?,?
657,TMP-C_T2I_ALEX_1121_1,HOLE_D10N,EMPTY,4,"H124,H125,H126,H127",?,?,?,?
658,TMP-QGND_HOLE12,GND_C8D4B8,EMPTY,2,"H111,H112",?,?,?,?
659,TP26,?,NA,2,"TP1,TP10",?,?,?,?
660,TP30,?,EMPTY,1,BATTERY_BT2,AHL03003097,?,?,?
661,TP30,?,EMPTY,1,BIOS_LABEL,HCLU2002010,?,?,?
662,TP30,?,EMPTY,1,J90_CON,DFHS56FR016,?,?,?
663,TP30,?,EMPTY,4,"JP12_12,JP4003_12,JP6000_12,JP6001_12",DEJP0020021,?,?,?
664,TP30,?,EMPTY,1,LBL_1,HCS6I019010,?,?,?
665,TP30,?,EMPTY,1,LBL_2,HCF0A001010,?,?,?
666,TP30,?,EMPTY,1,PJ38_NUT,MBF0E004010,?,?,?
667,TP30,?,NA,18,"TP2,TP3,TP4,TP5,TP6,TP7,TP8,TP9,TP11,TP12,TP13,TP14,TP15,TP16,TP17,TP18,TP19,TP20",?,?,?,?
668,TP30,?,EMPTY,2,"U25_BP,U26_BP",DGRA^600020,?,?,?
669,TP30,?,EMPTY,2,"U25_SRM,U26_SRM",DGRA^600000,?,?,?
670,TP33,Probe for DELTA-L 4.0 measurement,EMPTY,32,"J63,J64,J65,J66,J70,J71,J72,J73,J74,J75,J76,J77,J78,J79,J80,J81,J82,J83,J84,J85,J86,J114,J115,J116,J117,J118,J119,J120,J121,J8067,J8068,J8069",?,?,?,?
TOTAL, , , ,8335, , , , , 
